G04 ================== begin FILE IDENTIFICATION RECORD ==================*
G04 Layout Name:  12523-1.brd*
G04 Film Name:    DRILL*
G04 File Format:  Gerber RS274X*
G04 File Origin:  Cadence Allegro 16.2-s031*
G04 Origin Date:  Fri Oct 19 14:59:08 2012*
G04 *
G04 Layer:  MANUFACTURING/NCLEGEND-1-4*
G04 Layer:  MANUFACTURING/DRILL SIZE*
G04 Layer:  DRAWING FORMAT/LAYER_PCB_STORY*
G04 Layer:  DRAWING FORMAT/LAYER_DRILL*
G04 Layer:  BOARD GEOMETRY/PANEL_OUTLINE*
G04 *
G04 Offset:    (0.00 0.00)*
G04 Mirror:    No*
G04 Mode:      Positive*
G04 Rotation:  0*
G04 FullContactRelief:  No*
G04 UndefLineWidth:     6.00*
G04 ================== end FILE IDENTIFICATION RECORD ====================*
%FSLAX35Y35*MOIN*%
%IR0*IPPOS*OFA0.00000B0.00000*MIA0B0*SFA1.00000B1.00000*%
%AMMACRO10*
1,1,.006,0.0,.043*
20,1,.006,0.0,.043,.043,-.043,0.0*
1,1,.006,.043,-.043*
20,1,.006,.043,-.043,-.043,-.043,0.0*
1,1,.006,-.043,-.043*
20,1,.006,-.043,-.043,0.0,.043,0.0*
1,1,.006,0.0,.043*
1,1,.006,-.00143,-.0215*
20,1,.006,-.00143,-.0215,0.0,-.01218,0.0*
1,1,.006,0.0,-.01218*
20,1,.006,0.0,-.01218,.00215,-.0043,0.0*
1,1,.006,.00215,-.0043*
20,1,.006,.00215,-.0043,.00502,.00287,0.0*
1,1,.006,.00502,.00287*
20,1,.006,.00502,.00287,.0086,.01075,0.0*
1,1,.006,.0086,.01075*
20,1,.006,.0086,.01075,.01433,.0215,0.0*
1,1,.006,.01433,.0215*
20,1,.006,.01433,.0215,-.01433,.0215,0.0*
1,1,.006,-.01433,.0215*
%
%ADD10MACRO10*%
%AMMACRO12*
1,1,.006,.008,0.0*
20,1,.006,.008,0.0,-.008,0.0,0.0*
1,1,.006,-.008,0.0*
1,1,.006,0.0,.008*
20,1,.006,0.0,.008,0.0,-.008,0.0*
1,1,.006,0.0,-.008*
1,1,.006,.004,0.0*
20,1,.006,.004,0.0,.004,.008,0.0*
1,1,.006,.004,.008*
20,1,.006,.004,.008,.0024,.0064,0.0*
1,1,.006,.0024,.0064*
1,1,.006,.0024,0.0*
20,1,.006,.0024,0.0,.0056,0.0,0.0*
1,1,.006,.0056,0.0*
%
%ADD12MACRO12*%
%AMMACRO16*
1,1,.006,.0185,.0185*
20,1,.006,.0185,.0185,.0185,-.0185,0.0*
1,1,.006,.0185,-.0185*
20,1,.006,.0185,-.0185,-.0185,-.0185,0.0*
1,1,.006,-.0185,-.0185*
20,1,.006,-.0185,-.0185,-.0185,.0185,0.0*
1,1,.006,-.0185,.0185*
20,1,.006,-.0185,.0185,.0185,.0185,0.0*
1,1,.006,.0185,.0185*
1,1,.006,-.00586,.00617*
20,1,.006,-.00586,.00617,-.00401,.00802,0.0*
1,1,.006,-.00401,.00802*
20,1,.006,-.00401,.00802,-.00185,.00894,0.0*
1,1,.006,-.00185,.00894*
20,1,.006,-.00185,.00894,.00062,.00925,0.0*
1,1,.006,.00062,.00925*
20,1,.006,.00062,.00925,.0037,.00863,0.0*
1,1,.006,.0037,.00863*
20,1,.006,.0037,.00863,.00586,.00709,0.0*
1,1,.006,.00586,.00709*
20,1,.006,.00586,.00709,.00648,.00524,0.0*
1,1,.006,.00648,.00524*
20,1,.006,.00648,.00524,.00617,.00339,0.0*
1,1,.006,.00617,.00339*
20,1,.006,.00617,.00339,.00493,.00185,0.0*
1,1,.006,.00493,.00185*
20,1,.006,.00493,.00185,-.00123,-.00123,0.0*
1,1,.006,-.00123,-.00123*
20,1,.006,-.00123,-.00123,-.00401,-.00339,0.0*
1,1,.006,-.00401,-.00339*
20,1,.006,-.00401,-.00339,-.00586,-.00648,0.0*
1,1,.006,-.00586,-.00648*
20,1,.006,-.00586,-.00648,-.00648,-.00925,0.0*
1,1,.006,-.00648,-.00925*
20,1,.006,-.00648,-.00925,.00648,-.00925,0.0*
1,1,.006,.00648,-.00925*
%
%ADD16MACRO16*%
%AMMACRO15*
1,1,.006,.017,0.0*
20,1,.006,.017,0.0,0.0,-.017,0.0*
1,1,.006,0.0,-.017*
20,1,.006,0.0,-.017,-.017,0.0,0.0*
1,1,.006,-.017,0.0*
20,1,.006,-.017,0.0,0.0,.017,0.0*
1,1,.006,0.0,.017*
20,1,.006,0.0,.017,.017,0.0,0.0*
1,1,.006,.017,0.0*
1,1,.006,-.00538,-.00142*
20,1,.006,-.00538,-.00142,-.0034,.00057,0.0*
1,1,.006,-.0034,.00057*
20,1,.006,-.0034,.00057,-.0017,.0017,0.0*
1,1,.006,-.0017,.0017*
20,1,.006,-.0017,.0017,.00057,.00227,0.0*
1,1,.006,.00057,.00227*
20,1,.006,.00057,.00227,.00255,.0017,0.0*
1,1,.006,.00255,.0017*
20,1,.006,.00255,.0017,.00397,.00057,0.0*
1,1,.006,.00397,.00057*
20,1,.006,.00397,.00057,.0051,-.00113,0.0*
1,1,.006,.0051,-.00113*
20,1,.006,.0051,-.00113,.00538,-.00312,0.0*
1,1,.006,.00538,-.00312*
20,1,.006,.00538,-.00312,.0051,-.00482,0.0*
1,1,.006,.0051,-.00482*
20,1,.006,.0051,-.00482,.00397,-.00652,0.0*
1,1,.006,.00397,-.00652*
20,1,.006,.00397,-.00652,.00227,-.00793,0.0*
1,1,.006,.00227,-.00793*
20,1,.006,.00227,-.00793,.00028,-.0085,0.0*
1,1,.006,.00028,-.0085*
20,1,.006,.00028,-.0085,-.00198,-.00793,0.0*
1,1,.006,-.00198,-.00793*
20,1,.006,-.00198,-.00793,-.00397,-.00623,0.0*
1,1,.006,-.00397,-.00623*
20,1,.006,-.00397,-.00623,-.0051,-.00368,0.0*
1,1,.006,-.0051,-.00368*
20,1,.006,-.0051,-.00368,-.00538,-.00085,0.0*
1,1,.006,-.00538,-.00085*
20,1,.006,-.00538,-.00085,-.00482,.00283,0.0*
1,1,.006,-.00482,.00283*
20,1,.006,-.00482,.00283,-.00397,.00482,0.0*
1,1,.006,-.00397,.00482*
20,1,.006,-.00397,.00482,-.00255,.0068,0.0*
1,1,.006,-.00255,.0068*
20,1,.006,-.00255,.0068,-.00057,.00822,0.0*
1,1,.006,-.00057,.00822*
20,1,.006,-.00057,.00822,.00142,.0085,0.0*
1,1,.006,.00142,.0085*
20,1,.006,.00142,.0085,.0034,.00793,0.0*
1,1,.006,.0034,.00793*
20,1,.006,.0034,.00793,.00482,.00652,0.0*
1,1,.006,.00482,.00652*
%
%ADD15MACRO15*%
%AMMACRO13*
1,1,.006,.032723,-.079*
20,1,.006,.032723,-.079,-.032723,-.079,0.0*
1,1,.006,-.032723,-.079*
20,1,.006,-.032723,-.079,-.079,-.032723,0.0*
1,1,.006,-.079,-.032723*
20,1,.006,-.079,-.032723,-.079,.032723,0.0*
1,1,.006,-.079,.032723*
20,1,.006,-.079,.032723,-.032723,.079,0.0*
1,1,.006,-.032723,.079*
20,1,.006,-.032723,.079,.032723,.079,0.0*
1,1,.006,.032723,.079*
20,1,.006,.032723,.079,.079,.032723,0.0*
1,1,.006,.079,.032723*
20,1,.006,.079,.032723,.079,-.032723,0.0*
1,1,.006,.079,-.032723*
20,1,.006,.079,-.032723,.032723,-.079,0.0*
1,1,.006,.032723,-.079*
1,1,.006,-.02897,-.02765*
20,1,.006,-.02897,-.02765,-.02107,-.03423,0.0*
1,1,.006,-.02107,-.03423*
20,1,.006,-.02107,-.03423,-.01185,-.03818,0.0*
1,1,.006,-.01185,-.03818*
20,1,.006,-.01185,-.03818,0.0,-.0395,0.0*
1,1,.006,0.0,-.0395*
20,1,.006,0.0,-.0395,.01185,-.03687,0.0*
1,1,.006,.01185,-.03687*
20,1,.006,.01185,-.03687,.02107,-.0316,0.0*
1,1,.006,.02107,-.0316*
20,1,.006,.02107,-.0316,.02765,-.02238,0.0*
1,1,.006,.02765,-.02238*
20,1,.006,.02765,-.02238,.02897,-.01185,0.0*
1,1,.006,.02897,-.01185*
20,1,.006,.02897,-.01185,.02633,-.00132,0.0*
1,1,.006,.02633,-.00132*
20,1,.006,.02633,-.00132,.01975,.00527,0.0*
1,1,.006,.01975,.00527*
20,1,.006,.01975,.00527,.01053,.01053,0.0*
1,1,.006,.01053,.01053*
20,1,.006,.01053,.01053,.00132,.01185,0.0*
1,1,.006,.00132,.01185*
20,1,.006,.00132,.01185,-.0079,.01053,0.0*
1,1,.006,-.0079,.01053*
20,1,.006,-.0079,.01053,-.01975,.00527,0.0*
1,1,.006,-.01975,.00527*
20,1,.006,-.01975,.00527,-.0158,.0395,0.0*
1,1,.006,-.0158,.0395*
20,1,.006,-.0158,.0395,.01975,.0395,0.0*
1,1,.006,.01975,.0395*
%
%ADD13MACRO13*%
%AMMACRO11*
1,1,.006,0.0,.07*
20,1,.006,0.0,.07,-.060622,.035,0.0*
1,1,.006,-.060622,.035*
20,1,.006,-.060622,.035,-.060622,-.035,0.0*
1,1,.006,-.060622,-.035*
20,1,.006,-.060622,-.035,0.0,-.07,0.0*
1,1,.006,0.0,-.07*
20,1,.006,0.0,-.07,.060622,-.035,0.0*
1,1,.006,.060622,-.035*
20,1,.006,.060622,-.035,.060622,.035,0.0*
1,1,.006,.060622,.035*
20,1,.006,.060622,.035,0.0,.07,0.0*
1,1,.006,0.0,.07*
1,1,.006,.014,-.035*
20,1,.006,.014,-.035,.014,.035,0.0*
1,1,.006,.014,.035*
20,1,.006,.014,.035,-.02917,-.01517,0.0*
1,1,.006,-.02917,-.01517*
20,1,.006,-.02917,-.01517,.02917,-.01517,0.0*
1,1,.006,.02917,-.01517*
%
%ADD11MACRO11*%
%AMMACRO14*
1,1,.006,.0205,0.0*
20,1,.006,.0205,0.0,.01025,.017754,0.0*
1,1,.006,.01025,.017754*
20,1,.006,.01025,.017754,-.01025,.017754,0.0*
1,1,.006,-.01025,.017754*
20,1,.006,-.01025,.017754,-.0205,0.0,0.0*
1,1,.006,-.0205,0.0*
20,1,.006,-.0205,0.0,-.01025,-.017754,0.0*
1,1,.006,-.01025,-.017754*
20,1,.006,-.01025,-.017754,.01025,-.017754,0.0*
1,1,.006,.01025,-.017754*
20,1,.006,.01025,-.017754,.0205,0.0,0.0*
1,1,.006,.0205,0.0*
1,1,.006,-.00752,-.00615*
20,1,.006,-.00752,-.00615,-.00547,-.00854,0.0*
1,1,.006,-.00547,-.00854*
20,1,.006,-.00547,-.00854,-.00273,-.00991,0.0*
1,1,.006,-.00273,-.00991*
20,1,.006,-.00273,-.00991,.00034,-.01025,0.0*
1,1,.006,.00034,-.01025*
20,1,.006,.00034,-.01025,.00308,-.00991,0.0*
1,1,.006,.00308,-.00991*
20,1,.006,.00308,-.00991,.00581,-.0082,0.0*
1,1,.006,.00581,-.0082*
20,1,.006,.00581,-.0082,.00752,-.00615,0.0*
1,1,.006,.00752,-.00615*
20,1,.006,.00752,-.00615,.00786,-.0041,0.0*
1,1,.006,.00786,-.0041*
20,1,.006,.00786,-.0041,.00718,-.00171,0.0*
1,1,.006,.00718,-.00171*
20,1,.006,.00718,-.00171,.00478,0.0,0.0*
1,1,.006,.00478,0.0*
20,1,.006,.00478,0.0,.00239,.00068,0.0*
1,1,.006,.00239,.00068*
20,1,.006,.00239,.00068,-.00068,.00068,0.0*
1,1,.006,-.00068,.00068*
1,1,.006,.00239,.00068*
20,1,.006,.00239,.00068,.00444,.00171,0.0*
1,1,.006,.00444,.00171*
20,1,.006,.00444,.00171,.00615,.00342,0.0*
1,1,.006,.00615,.00342*
20,1,.006,.00615,.00342,.00683,.00547,0.0*
1,1,.006,.00683,.00547*
20,1,.006,.00683,.00547,.00615,.00752,0.0*
1,1,.006,.00615,.00752*
20,1,.006,.00615,.00752,.00444,.00922,0.0*
1,1,.006,.00444,.00922*
20,1,.006,.00444,.00922,.00137,.01025,0.0*
1,1,.006,.00137,.01025*
20,1,.006,.00137,.01025,-.00171,.00991,0.0*
1,1,.006,-.00171,.00991*
20,1,.006,-.00171,.00991,-.00478,.00854,0.0*
1,1,.006,-.00478,.00854*
%
%ADD14MACRO14*%
%AMMACRO17*
1,1,.006,0.0,.079*
20,1,.006,0.0,.079,0.0,.079,0.0*
1,1,.006,0.0,.079*
20,1,.006,0.0,.079,.013718,.0778,0.0*
1,1,.006,.013718,.0778*
20,1,.006,.013718,.0778,.02702,.074236,0.0*
1,1,.006,.02702,.074236*
20,1,.006,.02702,.074236,.0395,.068416,0.0*
1,1,.006,.0395,.068416*
20,1,.006,.0395,.068416,.05078,.060518,0.0*
1,1,.006,.05078,.060518*
20,1,.006,.05078,.060518,.060518,.05078,0.0*
1,1,.006,.060518,.05078*
20,1,.006,.060518,.05078,.068416,.0395,0.0*
1,1,.006,.068416,.0395*
20,1,.006,.068416,.0395,.074236,.02702,0.0*
1,1,.006,.074236,.02702*
20,1,.006,.074236,.02702,.0778,.013718,0.0*
1,1,.006,.0778,.013718*
20,1,.006,.0778,.013718,.079,0.0,0.0*
1,1,.006,.079,0.0*
20,1,.006,.079,0.0,.0778,-.013718,0.0*
1,1,.006,.0778,-.013718*
20,1,.006,.0778,-.013718,.074236,-.02702,0.0*
1,1,.006,.074236,-.02702*
20,1,.006,.074236,-.02702,.068416,-.0395,0.0*
1,1,.006,.068416,-.0395*
20,1,.006,.068416,-.0395,.060518,-.05078,0.0*
1,1,.006,.060518,-.05078*
20,1,.006,.060518,-.05078,.05078,-.060518,0.0*
1,1,.006,.05078,-.060518*
20,1,.006,.05078,-.060518,.0395,-.068416,0.0*
1,1,.006,.0395,-.068416*
20,1,.006,.0395,-.068416,.02702,-.074236,0.0*
1,1,.006,.02702,-.074236*
20,1,.006,.02702,-.074236,.013718,-.0778,0.0*
1,1,.006,.013718,-.0778*
20,1,.006,.013718,-.0778,0.0,-.079,0.0*
1,1,.006,0.0,-.079*
20,1,.006,0.0,-.079,0.0,-.079,0.0*
1,1,.006,0.0,-.079*
20,1,.006,0.0,-.079,-.013718,-.0778,0.0*
1,1,.006,-.013718,-.0778*
20,1,.006,-.013718,-.0778,-.02702,-.074236,0.0*
1,1,.006,-.02702,-.074236*
20,1,.006,-.02702,-.074236,-.0395,-.068416,0.0*
1,1,.006,-.0395,-.068416*
20,1,.006,-.0395,-.068416,-.05078,-.060518,0.0*
1,1,.006,-.05078,-.060518*
20,1,.006,-.05078,-.060518,-.060518,-.05078,0.0*
1,1,.006,-.060518,-.05078*
20,1,.006,-.060518,-.05078,-.068416,-.0395,0.0*
1,1,.006,-.068416,-.0395*
20,1,.006,-.068416,-.0395,-.074236,-.02702,0.0*
1,1,.006,-.074236,-.02702*
20,1,.006,-.074236,-.02702,-.0778,-.013718,0.0*
1,1,.006,-.0778,-.013718*
20,1,.006,-.0778,-.013718,-.079,0.0,0.0*
1,1,.006,-.079,0.0*
20,1,.006,-.079,0.0,-.0778,.013718,0.0*
1,1,.006,-.0778,.013718*
20,1,.006,-.0778,.013718,-.074236,.02702,0.0*
1,1,.006,-.074236,.02702*
20,1,.006,-.074236,.02702,-.068416,.0395,0.0*
1,1,.006,-.068416,.0395*
20,1,.006,-.068416,.0395,-.060518,.05078,0.0*
1,1,.006,-.060518,.05078*
20,1,.006,-.060518,.05078,-.05078,.060518,0.0*
1,1,.006,-.05078,.060518*
20,1,.006,-.05078,.060518,-.0395,.068416,0.0*
1,1,.006,-.0395,.068416*
20,1,.006,-.0395,.068416,-.02702,.074236,0.0*
1,1,.006,-.02702,.074236*
20,1,.006,-.02702,.074236,-.013718,.0778,0.0*
1,1,.006,-.013718,.0778*
20,1,.006,-.013718,.0778,0.0,.079,0.0*
1,1,.006,0.0,.079*
1,1,.006,0.0,-.0395*
20,1,.006,0.0,-.0395,.00922,-.03818,0.0*
1,1,.006,.00922,-.03818*
20,1,.006,.00922,-.03818,.01975,-.03423,0.0*
1,1,.006,.01975,-.03423*
20,1,.006,.01975,-.03423,.02633,-.02765,0.0*
1,1,.006,.02633,-.02765*
20,1,.006,.02633,-.02765,.02897,-.01843,0.0*
1,1,.006,.02897,-.01843*
20,1,.006,.02897,-.01843,.02633,-.00922,0.0*
1,1,.006,.02633,-.00922*
20,1,.006,.02633,-.00922,.01843,-.00132,0.0*
1,1,.006,.01843,-.00132*
20,1,.006,.01843,-.00132,.00658,.00263,0.0*
1,1,.006,.00658,.00263*
20,1,.006,.00658,.00263,-.00658,.00263,0.0*
1,1,.006,-.00658,.00263*
20,1,.006,-.00658,.00263,-.01448,.00527,0.0*
1,1,.006,-.01448,.00527*
20,1,.006,-.01448,.00527,-.02107,.01185,0.0*
1,1,.006,-.02107,.01185*
20,1,.006,-.02107,.01185,-.0237,.02107,0.0*
1,1,.006,-.0237,.02107*
20,1,.006,-.0237,.02107,-.01975,.03028,0.0*
1,1,.006,-.01975,.03028*
20,1,.006,-.01975,.03028,-.01053,.03687,0.0*
1,1,.006,-.01053,.03687*
20,1,.006,-.01053,.03687,0.0,.0395,0.0*
1,1,.006,0.0,.0395*
20,1,.006,0.0,.0395,.01053,.03687,0.0*
1,1,.006,.01053,.03687*
20,1,.006,.01053,.03687,.01975,.03028,0.0*
1,1,.006,.01975,.03028*
20,1,.006,.01975,.03028,.0237,.02107,0.0*
1,1,.006,.0237,.02107*
20,1,.006,.0237,.02107,.02107,.01185,0.0*
1,1,.006,.02107,.01185*
20,1,.006,.02107,.01185,.01448,.00527,0.0*
1,1,.006,.01448,.00527*
20,1,.006,.01448,.00527,.00658,.00263,0.0*
1,1,.006,.00658,.00263*
20,1,.006,.00658,.00263,-.00658,.00263,0.0*
1,1,.006,-.00658,.00263*
20,1,.006,-.00658,.00263,-.01843,-.00132,0.0*
1,1,.006,-.01843,-.00132*
20,1,.006,-.01843,-.00132,-.02633,-.00922,0.0*
1,1,.006,-.02633,-.00922*
20,1,.006,-.02633,-.00922,-.02897,-.01843,0.0*
1,1,.006,-.02897,-.01843*
20,1,.006,-.02897,-.01843,-.02633,-.02765,0.0*
1,1,.006,-.02633,-.02765*
20,1,.006,-.02633,-.02765,-.01975,-.03423,0.0*
1,1,.006,-.01975,-.03423*
20,1,.006,-.01975,-.03423,-.00922,-.03818,0.0*
1,1,.006,-.00922,-.03818*
20,1,.006,-.00922,-.03818,0.0,-.0395,0.0*
1,1,.006,0.0,-.0395*
%
%ADD17MACRO17*%
%ADD18C,.02*%
%ADD19C,.006*%
G75*
%LPD*%
G75*
G54D10*
X-23621Y15748D03*
Y937008D03*
X1312285Y15747D03*
X1514950Y125650D03*
G54D11*
X30157Y61023D03*
Y415354D03*
X1514950Y209950D03*
G54D12*
X6419Y116482D03*
X-3350Y117504D03*
X6419Y126482D03*
X-3581D03*
X6419Y136482D03*
X-3581D03*
X6419Y146482D03*
X-3581D03*
X6419Y156482D03*
X-3581D03*
X-2602Y206936D03*
X7398D03*
X-2602Y216936D03*
X7398D03*
X6419Y166482D03*
X-3581D03*
Y176482D03*
X6419D03*
X-2602Y226936D03*
X7398D03*
X-2602Y246936D03*
X7398D03*
X-2602Y236936D03*
X7398D03*
Y256936D03*
X-2602D03*
Y266936D03*
X7398D03*
Y276936D03*
X-2602D03*
X7398Y286936D03*
X3398Y326936D03*
X-2948Y302202D03*
X-2602Y316436D03*
X-7102Y327202D03*
X-6940Y316247D03*
X2334Y318654D03*
X1494Y343705D03*
X5694D03*
X-6602Y347202D03*
X-7102Y337202D03*
X-6602Y357202D03*
X6898Y387436D03*
X6398Y369936D03*
X6898Y445436D03*
Y465436D03*
X16419Y6482D03*
Y26482D03*
X36419Y6482D03*
Y26482D03*
X56419Y46482D03*
X16419Y86482D03*
X36419D03*
X56419Y66482D03*
Y86482D03*
X26419Y116482D03*
X16419D03*
X26419Y126482D03*
X16419D03*
X26419Y136482D03*
X16419D03*
X26419Y146482D03*
X16419D03*
X26419Y156482D03*
X16419D03*
X36419Y126482D03*
X16419Y106482D03*
X36419D03*
Y146482D03*
X56419Y126482D03*
Y106482D03*
Y146482D03*
X27398Y206936D03*
X17398D03*
X27398Y216936D03*
X17398D03*
X26419Y186482D03*
X16419D03*
X26419Y166482D03*
X16419D03*
Y176482D03*
X26419D03*
X36419Y186482D03*
Y166482D03*
X56419Y186482D03*
Y166482D03*
X57398Y206936D03*
X37398D03*
X17398Y256936D03*
X27398D03*
Y266936D03*
X17398D03*
X57398Y226936D03*
X36769D03*
X57398Y246936D03*
Y266936D03*
X36769Y246936D03*
X37398Y266936D03*
X17398Y276936D03*
X27398Y286936D03*
X17398D03*
X27398Y276936D03*
X10000Y332000D03*
X57398Y286936D03*
X37398D03*
X64398Y304436D03*
X30923Y335665D03*
X25500Y353000D03*
X25000Y343000D03*
X33986Y362933D03*
X26723Y335665D03*
X22000Y374500D03*
X34898Y344936D03*
X57398Y348682D03*
X52705Y348626D03*
X48325Y348514D03*
X62398Y338436D03*
X37500Y386500D03*
X22000Y387500D03*
X61898Y358936D03*
X62000Y442500D03*
X60052Y394674D03*
X35830Y442464D03*
X55352Y394674D03*
X51094Y394478D03*
X55500Y417000D03*
X19898Y465436D03*
X39898D03*
X76419Y46482D03*
X116419D03*
X96419D03*
X76419Y66482D03*
Y86482D03*
X116419Y66482D03*
X96419D03*
X116419Y86482D03*
X96419D03*
X76419Y126482D03*
Y106482D03*
Y146482D03*
X116419Y126482D03*
Y106482D03*
X96419Y126482D03*
Y106482D03*
X116419Y146482D03*
X96419D03*
X76419Y186482D03*
Y166482D03*
X77398Y206936D03*
X116419Y186482D03*
Y166482D03*
X96419Y186482D03*
Y166482D03*
X117398Y206936D03*
X97398D03*
X77398Y226936D03*
Y246936D03*
Y266936D03*
X117398Y226936D03*
X97398D03*
X117398Y246936D03*
X97398D03*
Y266936D03*
X116398D03*
X77398Y286936D03*
X86398Y303936D03*
X97398Y286936D03*
X116398D03*
X77898Y338436D03*
X78398Y358436D03*
X115330Y337964D03*
X96398Y337936D03*
X115330Y377964D03*
Y357964D03*
X95330Y377964D03*
Y357964D03*
X105330Y442964D03*
X85330D03*
X75500Y417500D03*
X115330Y417964D03*
X95330D03*
X91500Y465500D03*
X117500D03*
X67830Y465464D03*
X136419Y6482D03*
Y46482D03*
X176419Y6482D03*
Y26482D03*
X156419Y6482D03*
Y26482D03*
X176419Y46482D03*
X156419D03*
X136419Y66482D03*
Y86482D03*
X176419Y66482D03*
X156419D03*
X176419Y86482D03*
X156419D03*
X136419Y126482D03*
Y106482D03*
Y146482D03*
X176419Y126482D03*
Y106482D03*
X156419Y126482D03*
Y106482D03*
X176419Y146482D03*
X156419D03*
X136419Y186482D03*
Y166482D03*
X137398Y206936D03*
X176419Y186482D03*
Y166482D03*
X156419Y186482D03*
Y166482D03*
X177398Y206436D03*
X157398Y206936D03*
X137398Y226936D03*
Y246936D03*
Y266936D03*
X177398Y226936D03*
X157398D03*
X177398Y246936D03*
Y266936D03*
X157398Y246936D03*
Y266936D03*
X137398Y286936D03*
X177398D03*
X157398D03*
X135330Y337964D03*
Y377964D03*
Y357964D03*
X175330Y337964D03*
X155330D03*
X175330Y377964D03*
Y357964D03*
X155330Y377964D03*
Y357964D03*
X132000Y442500D03*
X135330Y417964D03*
X175500Y442000D03*
X175330Y417964D03*
X155000Y442000D03*
X155330Y417964D03*
X139898Y465436D03*
X159898D03*
X196419Y6482D03*
Y26482D03*
Y46482D03*
X236419Y6482D03*
Y26482D03*
X216419Y6482D03*
Y26482D03*
X236419Y46482D03*
X216419D03*
X196419Y66482D03*
Y86482D03*
X236419Y66482D03*
X216419D03*
X236419Y86482D03*
X216419D03*
X196419Y126482D03*
Y106482D03*
Y146482D03*
X236419Y126482D03*
Y106482D03*
X216419Y126482D03*
Y106482D03*
X236419Y146482D03*
X216419D03*
X196419Y186482D03*
Y166482D03*
X197398Y206436D03*
X236419Y186482D03*
Y166482D03*
X216419Y186482D03*
Y166482D03*
X217398Y206436D03*
X197398Y226936D03*
Y246936D03*
Y266936D03*
X217398Y226936D03*
Y246936D03*
Y266936D03*
X197398Y286936D03*
X217398D03*
X195330Y337964D03*
Y377964D03*
Y357964D03*
X235330Y337964D03*
X215330D03*
X235330Y377964D03*
Y357964D03*
X215330Y377964D03*
Y357964D03*
X196000Y442500D03*
X195330Y417964D03*
X235830Y442464D03*
X235330Y417964D03*
X215830Y442464D03*
X215330Y417964D03*
X179898Y465436D03*
X219898D03*
X199898D03*
X256419Y6482D03*
Y26482D03*
X276419Y6482D03*
Y26482D03*
X256419Y46482D03*
X276419D03*
X256419Y66482D03*
X273500Y66500D03*
X256419Y86482D03*
X274500Y86500D03*
X256419Y126482D03*
X276419D03*
X256419Y106482D03*
X274500Y106500D03*
X256419Y146482D03*
X276419D03*
X237398Y206436D03*
X256419Y186482D03*
X275500Y186500D03*
X251500Y166500D03*
X276419Y166482D03*
X257398Y206436D03*
X277398D03*
X237398Y226936D03*
Y246936D03*
Y266936D03*
X257398Y226936D03*
X277398D03*
X257398Y246936D03*
X277398D03*
X257398Y266936D03*
X277398D03*
X237398Y286936D03*
X257398D03*
X279398D03*
X255330Y337964D03*
X275330D03*
X255330Y377964D03*
X275330D03*
X255330Y357964D03*
X275330D03*
X255830Y442464D03*
X275830D03*
X255330Y417964D03*
X275330D03*
X239898Y465436D03*
X279898D03*
X259898D03*
X296419Y6482D03*
Y26482D03*
Y46482D03*
X316419Y6482D03*
Y26482D03*
X336419Y6482D03*
Y26482D03*
X316419Y46482D03*
X336419D03*
X302000Y67000D03*
X301000Y86500D03*
X316419Y66482D03*
X336419D03*
X316419Y86482D03*
X336419D03*
X296419Y126482D03*
X300000Y106500D03*
X296419Y146482D03*
X316419Y126482D03*
X336419D03*
X316419Y106482D03*
X336419D03*
X316419Y146482D03*
X336419D03*
X296419Y186482D03*
X295500Y169000D03*
X297398Y206436D03*
X317500Y186500D03*
X336419Y186482D03*
X317000Y166500D03*
X338500Y166000D03*
X317398Y206436D03*
X337398D03*
X297398Y226936D03*
Y246936D03*
Y266936D03*
X317398Y226936D03*
X337398D03*
X317398Y246936D03*
X337398D03*
X317398Y266936D03*
X337398D03*
X300398Y286936D03*
X317398D03*
X337398D03*
X295330Y337964D03*
Y377964D03*
Y357964D03*
X315330Y337964D03*
X335330D03*
X315330Y377964D03*
X335330D03*
X315330Y357964D03*
X335330D03*
X295830Y442464D03*
X295330Y417964D03*
X315830Y442464D03*
X335830D03*
X315330Y417964D03*
X335330D03*
X299898Y465436D03*
X339898D03*
X319898D03*
X356419Y6482D03*
Y26482D03*
Y46482D03*
X376419Y6482D03*
Y26482D03*
X396419Y6482D03*
Y26482D03*
X376419Y46482D03*
X396419D03*
X356419Y66482D03*
Y86482D03*
X376419Y66482D03*
X396419D03*
X376419Y86482D03*
X396419D03*
X356419Y126482D03*
Y106482D03*
Y146482D03*
X376419Y126482D03*
X396419D03*
X376419Y106482D03*
X396419D03*
X376419Y146482D03*
X396419D03*
X357500Y186500D03*
X354500Y166500D03*
X357398Y206436D03*
X376419Y186482D03*
X396419D03*
X380000Y166500D03*
X396419Y166482D03*
X377398Y206436D03*
X397398D03*
X357398Y226936D03*
Y246936D03*
Y266936D03*
X377398Y226936D03*
X397398D03*
X377398Y246936D03*
X397398D03*
X377398Y266936D03*
X397398D03*
X357398Y286936D03*
X377398D03*
X397398D03*
X355330Y337964D03*
Y377964D03*
Y357964D03*
X375330Y337964D03*
X395330D03*
X375330Y377964D03*
X395330D03*
X375330Y357964D03*
X395330D03*
X355830Y442464D03*
X355330Y417964D03*
X375830Y442464D03*
X395830D03*
X375330Y417964D03*
X395330D03*
X399898Y465436D03*
X379898D03*
X359898D03*
X416419Y6482D03*
Y26482D03*
X436419Y6482D03*
X416419Y46482D03*
X436419D03*
X456419D03*
X416419Y66482D03*
X436419D03*
X456419D03*
X416419Y86482D03*
X436419D03*
X456419D03*
X416419Y126482D03*
X436419D03*
X456419D03*
X416419Y106482D03*
X436419D03*
X456419D03*
X416419Y146482D03*
X436419D03*
X456419D03*
X416500Y166000D03*
X417519Y174482D03*
Y170282D03*
X425919D03*
X421719D03*
Y174482D03*
X431100Y174500D03*
Y170300D03*
X439500D03*
Y174500D03*
X435300Y170300D03*
Y174500D03*
X444100D03*
Y170300D03*
X452500D03*
Y174500D03*
X448300Y170300D03*
Y174500D03*
X457100Y175000D03*
Y170800D03*
X461300D03*
Y175000D03*
X418300Y197500D03*
Y201700D03*
X422500D03*
X426700D03*
X422500Y197500D03*
X426700D03*
X431300D03*
Y201700D03*
X435500D03*
X439700D03*
X435500Y197500D03*
X439700D03*
X444800D03*
Y201700D03*
X449000D03*
X453200D03*
X449000Y197500D03*
X453200D03*
X457800D03*
Y201700D03*
X462000D03*
Y197500D03*
X425919Y174482D03*
X436500Y166000D03*
X456500Y166500D03*
X417398Y206436D03*
X437398D03*
X457398D03*
X417398Y226936D03*
X437398D03*
X457398D03*
X417398Y246936D03*
X437398D03*
X457398D03*
X437398Y266936D03*
X457398D03*
X418398D03*
X437398Y286936D03*
X457398D03*
X418398D03*
X415330Y337964D03*
X435398Y338436D03*
X455398D03*
X415330Y377964D03*
Y357964D03*
X435398Y358436D03*
Y378436D03*
X455398Y358436D03*
Y378436D03*
X435830Y442464D03*
X455830D03*
X435330Y417964D03*
X455330D03*
X415830Y442464D03*
X415330Y417964D03*
X459898Y465436D03*
X439898D03*
X419898D03*
X516419Y6482D03*
X476419Y46482D03*
X496419D03*
X516419D03*
Y66482D03*
X476419D03*
X496419D03*
X516419Y86482D03*
X496419D03*
X476419D03*
Y126482D03*
X516419D03*
X496419D03*
X516419Y106482D03*
X496419D03*
X476419D03*
X485443Y160670D03*
X481243D03*
X493843D03*
X489643D03*
X476419Y146482D03*
X516419D03*
X496419D03*
X519221Y160912D03*
X510821D03*
X506621D03*
X515021D03*
X465500Y170800D03*
Y175000D03*
X466200Y201700D03*
Y197500D03*
X485443Y164870D03*
X481243D03*
X493843D03*
X489643D03*
X477284Y174586D03*
X473084D03*
Y170386D03*
X477284D03*
X498395Y174685D03*
Y170485D03*
X492911Y206602D03*
X488711D03*
X492911Y210802D03*
X488711D03*
X484511D03*
Y206602D03*
X480311Y210802D03*
Y206602D03*
X498052Y200389D03*
Y196189D03*
X477087Y201172D03*
X472887D03*
X477087Y196972D03*
X472887D03*
X519221Y165112D03*
X510821D03*
X506621D03*
X515021D03*
X502595Y174685D03*
Y170485D03*
X506135Y210557D03*
X510335D03*
X514535D03*
X518735D03*
X506135Y206357D03*
X510335D03*
X514535D03*
X518735D03*
X502252Y200389D03*
Y196189D03*
X497398Y226936D03*
X477398D03*
X520898Y228436D03*
X497398Y246936D03*
X477398D03*
Y266936D03*
X512500Y323000D03*
X492000Y321000D03*
X506500Y305500D03*
X520500Y331000D03*
X520381Y300757D03*
X495398Y338436D03*
X475398D03*
X495398Y358436D03*
Y378436D03*
X475398Y358436D03*
Y378436D03*
X477000Y418000D03*
X499000Y418500D03*
X485510Y442620D03*
X505510D03*
X519898Y465436D03*
X499898D03*
X479898D03*
X533619Y6482D03*
Y26482D03*
Y46482D03*
X550819Y6482D03*
Y26482D03*
Y46482D03*
X568019Y6482D03*
Y26482D03*
Y46482D03*
X573623Y66967D03*
X536419Y66482D03*
X556419D03*
X536419Y86482D03*
X556419D03*
X576419Y106482D03*
Y126482D03*
X536419D03*
X556419D03*
X536419Y106482D03*
X556419D03*
X544476Y161322D03*
X531876D03*
X536076D03*
X540276D03*
X536419Y146482D03*
X556419D03*
X544477Y210389D03*
X544476Y165522D03*
X536076D03*
X531876D03*
X540276D03*
X552924Y175124D03*
X548724D03*
Y170924D03*
X552924D03*
X527711Y175174D03*
X523511D03*
Y170974D03*
X527711D03*
X531877Y210389D03*
X536077D03*
X540277D03*
X531877Y206189D03*
X536077D03*
X540277D03*
X544477D03*
X527761Y200632D03*
X523561D03*
X527761Y196432D03*
X523561D03*
X553171Y200877D03*
X548971D03*
X553171Y196677D03*
X548971D03*
X546600Y257971D03*
X540898Y228436D03*
X561500Y232000D03*
X557000Y231500D03*
X560500Y268000D03*
X549500Y305500D03*
X543900Y314000D03*
X559996Y282972D03*
X561500Y298000D03*
X534000Y282000D03*
X537136Y326402D03*
X525161Y311000D03*
X577500Y305000D03*
X634119Y26482D03*
X585219Y46482D03*
Y26482D03*
Y6482D03*
X602419Y26482D03*
Y6482D03*
X619619D03*
Y26482D03*
Y46482D03*
X634119D03*
Y6482D03*
X602419Y46482D03*
X628500Y104000D03*
X626500Y78500D03*
X611253Y65701D03*
X584543Y86671D03*
X611398Y86936D03*
X633753Y65701D03*
X633898Y86936D03*
X634000Y123500D03*
X607000D03*
X616000Y138000D03*
Y115500D03*
X594500Y117000D03*
X616000Y173500D03*
X615500Y199000D03*
X615898Y244436D03*
Y224436D03*
X615398Y266436D03*
X587500Y318500D03*
X600000Y298500D03*
X616498Y316236D03*
X615398Y284436D03*
X633398Y325436D03*
X630000Y345500D03*
X600000Y337500D03*
Y342000D03*
X595500D03*
Y337500D03*
X630000Y387500D03*
X612798Y413000D03*
X610898Y425436D03*
Y445436D03*
X617798Y413000D03*
X632898Y404936D03*
Y444936D03*
Y424936D03*
X610898Y465436D03*
X632898Y464936D03*
X1514950Y294250D03*
G54D13*
X498661Y23622D03*
X589212Y448818D03*
X1514950Y181850D03*
G54D14*
X570709Y161889D03*
X580709D03*
X570709Y214409D03*
X580709D03*
X570709Y204409D03*
X580709D03*
X570709Y191889D03*
X580709D03*
X570709Y181889D03*
X580709D03*
X570709Y171889D03*
X580709D03*
X570709Y244409D03*
X580709D03*
X570709Y276929D03*
X580709D03*
X570709Y266929D03*
X580709D03*
X570709Y256929D03*
X580709D03*
X570709Y234409D03*
X580709D03*
X570709Y224409D03*
X580709D03*
X570709Y286929D03*
X580709D03*
X590709Y161889D03*
X600709D03*
X590709Y214409D03*
X600709D03*
X590709Y204409D03*
X600709D03*
X590709Y191889D03*
X600709D03*
X590709Y181889D03*
X600709D03*
X590709Y171889D03*
X600709D03*
X590709Y244409D03*
X600709D03*
X590709Y276929D03*
X600709D03*
X590709Y266929D03*
X600709D03*
X590709Y256929D03*
X600709D03*
X590709Y234409D03*
X600709D03*
X590709Y224409D03*
X600709D03*
X590709Y286929D03*
X600709D03*
X1514950Y238050D03*
G54D15*
X599055Y59055D03*
Y90551D03*
X1514950Y153750D03*
G54D16*
X596102Y66929D03*
X602008Y74803D03*
X596102Y82677D03*
X1514950Y266150D03*
G54D17*
X600709Y136909D03*
Y311909D03*
X1514950Y97550D03*
G54D18*
G01X-4246Y-109426D02*
Y-189426D01*
G01D02*
X1290354D01*
G01X-4246Y-144926D02*
X1290354D01*
G01X-8246Y-93426D02*
G02I-12000J0D01*
G01X-13396D02*
G02I-6850J0D01*
G01X-20246Y-109426D02*
Y-77426D01*
G01X-4246Y-93426D02*
X-36246D01*
G01X-4246Y-109426D02*
X1290354D01*
G01X502854D02*
Y-189426D01*
G01X640354Y-109426D02*
Y-189426D01*
G01X755354Y-109426D02*
Y-189426D01*
G01X922854Y-109426D02*
Y-189426D01*
G01X1092854Y-109426D02*
Y-189426D01*
G01X1290354Y-109426D02*
Y-189426D01*
G01X1318354Y-93426D02*
G02I-12000J0D01*
G01X1313204D02*
G02I-6850J0D01*
G01X1306354Y-109426D02*
Y-77426D01*
G01X1322354Y-93426D02*
X1290354D01*
G54D19*
G01X85820Y-19685D02*
X-29308D01*
G01X-43308Y-5685D02*
G03X-29308Y-19685I14000J0D01*
G01X0Y3937D02*
Y106969D01*
G01Y3937D02*
Y106969D01*
G01X636457Y0D02*
X3937D01*
G01X636457D02*
X3937D01*
G01X0Y3937D02*
G03X3937Y0I3937J0D01*
G01X0Y3937D02*
G03X3937Y0I3937J0D01*
G01X-43308Y-5685D02*
Y103032D01*
G01X-7874Y50259D02*
Y3937D01*
G01D02*
G03X3937Y-7874I11811J0D01*
G01D02*
X77283D01*
G01X-7874Y103032D02*
Y75456D01*
G01Y75460D02*
G03X0I3937J0D01*
G01Y50259D02*
G03X-7874I-3937J0D01*
G01X-43307Y286142D02*
Y116811D01*
G01D02*
X-37402Y110906D01*
G01X-41339Y114843D02*
X-37402Y110906D01*
G01D02*
X-3937D01*
G01X-37402D02*
X-3937D01*
G01X0Y106969D02*
G03X-3937Y110906I-3937J0D01*
G01X0Y106969D02*
G03X-3937Y110906I-3937J0D01*
G01X-43308Y103032D02*
X-7874D01*
G01X-43307Y360039D02*
Y300709D01*
G01X-37402Y292047D02*
X-41339Y288110D01*
G01X-37402Y292047D02*
X-43307Y286142D01*
G01Y300709D02*
X-37402Y294803D01*
G01X-41339Y298740D02*
X-37402Y294803D01*
G01X-12598Y292047D02*
X-37402D01*
G01D02*
X-1378D01*
G01X-12598D02*
X-1378D01*
G01X-37402Y294803D02*
X-1378D01*
G01X-37402D02*
X-1378D01*
G01Y292047D02*
G03Y294803I0J1378D01*
G01Y292047D02*
G03Y294803I0J1378D01*
G01X-37402Y365945D02*
X-41339Y362008D01*
G01X-37402Y365945D02*
X-43307Y360039D01*
G01X0Y369882D02*
Y468504D01*
G01Y369882D02*
Y468504D01*
G01X-3937Y365945D02*
X-37402D01*
G01X-3937D02*
X-37402D01*
G01X-3937D02*
G03X0Y369882I0J3937D01*
G01X-3937Y365945D02*
G03X0Y369882I0J3937D01*
G01X-7874Y401397D02*
Y373819D01*
G01D02*
X-43307D01*
G01D02*
X-43308Y373820D01*
G01D02*
Y583347D01*
G01X0Y401397D02*
G03X-7874I-3937J0D01*
G01Y426594D02*
G03X0I3937J0D01*
G01X-7874D02*
Y530574D01*
G01X3937Y472441D02*
X636457D01*
G01X3937D02*
X636457D01*
G01X3937D02*
G03X0Y468504I0J-3937D01*
G01X3937Y472441D02*
G03X0Y468504I0J-3937D01*
G01Y484252D02*
Y587283D01*
G01Y484252D02*
Y587283D01*
G01X636457Y480315D02*
X3937D01*
G01X636457D02*
X3937D01*
G01X0Y484252D02*
G03X3937Y480315I3937J0D01*
G01X0Y484252D02*
G03X3937Y480315I3937J0D01*
G01X-7874Y583347D02*
Y555771D01*
G01D02*
G03X0I3937J0D01*
G01Y530574D02*
G03X-7874I-3937J0D01*
G01X-43307Y766457D02*
Y597126D01*
G01D02*
X-37402Y591220D01*
G01X-41339Y595157D02*
X-37402Y591220D01*
G01D02*
X-3937D01*
G01X-37402D02*
X-3937D01*
G01X0Y587283D02*
G03X-3937Y591220I-3937J0D01*
G01X0Y587283D02*
G03X-3937Y591220I-3937J0D01*
G01X-43308Y583347D02*
X-7874D01*
G01X-43307Y840354D02*
Y781024D01*
G01X-37402Y772362D02*
X-41339Y768425D01*
G01X-37402Y772362D02*
X-43307Y766457D01*
G01Y781024D02*
X-37402Y775118D01*
G01X-41339Y779055D02*
X-37402Y775118D01*
G01X-12598Y772362D02*
X-37402D01*
G01D02*
X-1378D01*
G01X-12598D02*
X-1378D01*
G01X-37402Y775118D02*
X-1378D01*
G01X-37402D02*
X-1378D01*
G01Y772362D02*
G03Y775118I0J1378D01*
G01Y772362D02*
G03Y775118I0J1378D01*
G01X-37402Y846260D02*
X-41339Y842323D01*
G01X-37402Y846260D02*
X-43307Y840354D01*
G01X0Y850197D02*
Y948819D01*
G01Y850197D02*
Y948819D01*
G01X-3937Y846260D02*
X-37402D01*
G01X-3937D02*
X-37402D01*
G01X-3937D02*
G03X0Y850197I0J3937D01*
G01X-3937Y846260D02*
G03X0Y850197I0J3937D01*
G01X-7874Y881712D02*
Y854134D01*
G01D02*
X-43308D01*
G01D02*
Y958441D01*
G01X0Y881711D02*
G03X-7874I-3937J0D01*
G01X3937Y952756D02*
X636457D01*
G01X3937D02*
X636457D01*
G01X3937D02*
G03X0Y948819I0J-3937D01*
G01X3937Y952756D02*
G03X0Y948819I0J-3937D01*
G01X-29308Y972441D02*
G03X-43308Y958441I0J-14000D01*
G01X-7874Y906909D02*
G03X0I3937J0D01*
G01X-7874D02*
Y948819D01*
G01X3937Y960630D02*
G03X-7874Y948819I0J-11811D01*
G01X-29308Y972441D02*
X1317968D01*
G01X3937Y960630D02*
X77283D01*
G01X16751Y-179426D02*
Y-161926D01*
G01X25047D02*
X16751Y-172718D01*
G01X26357Y-179426D02*
X20462Y-167760D01*
G01X34032Y-179426D02*
Y-161926D01*
X44076Y-179426D01*
Y-161926D01*
G01X56554Y-179426D02*
X54807Y-179134D01*
X53279Y-177968D01*
X51969Y-176218D01*
X51095Y-174176D01*
X50659Y-171843D01*
Y-169509D01*
X51095Y-167176D01*
X51969Y-165134D01*
X53279Y-163385D01*
X54807Y-162218D01*
X56554Y-161926D01*
X58300Y-162218D01*
X59829Y-163385D01*
X61139Y-165134D01*
X62013Y-167176D01*
X62449Y-169509D01*
Y-171843D01*
X62013Y-174176D01*
X61139Y-176218D01*
X59829Y-177968D01*
X58300Y-179134D01*
X56554Y-179426D01*
G01X69469D02*
X78639Y-161926D01*
G01X69469D02*
X78639Y-179426D01*
G01X104687D02*
Y-161926D01*
X109927D01*
X111674Y-162801D01*
X112984Y-164843D01*
X113421Y-167176D01*
X112984Y-169509D01*
X111892Y-171259D01*
X109927Y-172135D01*
X104687D01*
G01X126554Y-179426D02*
X124807Y-179134D01*
X123279Y-177968D01*
X121969Y-176218D01*
X121095Y-174176D01*
X120659Y-171843D01*
Y-169509D01*
X121095Y-167176D01*
X121969Y-165134D01*
X123279Y-163385D01*
X124807Y-162218D01*
X126554Y-161926D01*
X128300Y-162218D01*
X129829Y-163385D01*
X131139Y-165134D01*
X132013Y-167176D01*
X132449Y-169509D01*
Y-171843D01*
X132013Y-174176D01*
X131139Y-176218D01*
X129829Y-177968D01*
X128300Y-179134D01*
X126554Y-179426D01*
G01X137504Y-161926D02*
X140560Y-179426D01*
X144054Y-161926D01*
X147547Y-179426D01*
X150604Y-161926D01*
G01X165921Y-179426D02*
X157187D01*
Y-161926D01*
X165921D01*
G01X162427Y-170384D02*
X157187D01*
G01X174687Y-179426D02*
Y-161926D01*
X180146D01*
X181892Y-162801D01*
X182984Y-163968D01*
X183421Y-166301D01*
X182984Y-168635D01*
X181674Y-170093D01*
X180146Y-170968D01*
X174687D01*
G01X180146D02*
X183421Y-179426D01*
G01X214054Y-161926D02*
Y-179426D01*
G01X209032Y-161926D02*
X219076D01*
G01X227187Y-179426D02*
Y-161926D01*
X232646D01*
X234392Y-162801D01*
X235484Y-163968D01*
X235921Y-166301D01*
X235484Y-168635D01*
X234174Y-170093D01*
X232646Y-170968D01*
X227187D01*
G01X232646D02*
X235921Y-179426D01*
G01X243595D02*
X249054Y-161926D01*
X254513Y-179426D01*
G01X252547Y-173301D02*
X245560D01*
G01X261532Y-179426D02*
Y-161926D01*
X271576Y-179426D01*
Y-161926D01*
G01X279469Y-177093D02*
X281216Y-178551D01*
X283181Y-179426D01*
X284927D01*
X286674Y-178551D01*
X287984Y-177093D01*
X288639Y-175051D01*
X288202Y-173010D01*
X287111Y-171259D01*
X285146Y-170093D01*
X282526Y-169509D01*
X280997Y-168343D01*
X280342Y-166301D01*
X280779Y-164259D01*
X281871Y-162801D01*
X283399Y-161926D01*
X284927D01*
X286456Y-162509D01*
X287766Y-163968D01*
G01X298934Y-161926D02*
X304174D01*
G01X301554D02*
Y-179426D01*
G01X298934D02*
X304174D01*
G01X319054Y-161926D02*
Y-179426D01*
G01X314032Y-161926D02*
X324076D01*
G01X333934D02*
X339174D01*
G01X336554D02*
Y-179426D01*
G01X333934D02*
X339174D01*
G01X354054D02*
X352307Y-179134D01*
X350779Y-177968D01*
X349469Y-176218D01*
X348595Y-174176D01*
X348159Y-171843D01*
Y-169509D01*
X348595Y-167176D01*
X349469Y-165134D01*
X350779Y-163385D01*
X352307Y-162218D01*
X354054Y-161926D01*
X355800Y-162218D01*
X357329Y-163385D01*
X358639Y-165134D01*
X359513Y-167176D01*
X359949Y-169509D01*
Y-171843D01*
X359513Y-174176D01*
X358639Y-176218D01*
X357329Y-177968D01*
X355800Y-179134D01*
X354054Y-179426D01*
G01X366532D02*
Y-161926D01*
X376576Y-179426D01*
Y-161926D01*
G01X408300Y-170093D02*
X409174Y-169218D01*
X409829Y-167760D01*
X410266Y-165717D01*
X409829Y-163968D01*
X408956Y-162801D01*
X407427Y-161926D01*
X401532D01*
Y-179426D01*
X408737D01*
X410266Y-178260D01*
X411139Y-176509D01*
X411576Y-174468D01*
X411139Y-172426D01*
X409829Y-170676D01*
X408300Y-170093D01*
X401532D01*
G01X424054Y-179426D02*
X422307Y-179134D01*
X420779Y-177968D01*
X419469Y-176218D01*
X418595Y-174176D01*
X418159Y-171843D01*
Y-169509D01*
X418595Y-167176D01*
X419469Y-165134D01*
X420779Y-163385D01*
X422307Y-162218D01*
X424054Y-161926D01*
X425800Y-162218D01*
X427329Y-163385D01*
X428639Y-165134D01*
X429513Y-167176D01*
X429949Y-169509D01*
Y-171843D01*
X429513Y-174176D01*
X428639Y-176218D01*
X427329Y-177968D01*
X425800Y-179134D01*
X424054Y-179426D01*
G01X436095D02*
X441554Y-161926D01*
X447013Y-179426D01*
G01X445047Y-173301D02*
X438060D01*
G01X454687Y-179426D02*
Y-161926D01*
X460146D01*
X461892Y-162801D01*
X462984Y-163968D01*
X463421Y-166301D01*
X462984Y-168635D01*
X461674Y-170093D01*
X460146Y-170968D01*
X454687D01*
G01X460146D02*
X463421Y-179426D01*
G01X471751D02*
Y-161926D01*
X476117D01*
X477864Y-162801D01*
X479174Y-163968D01*
X480266Y-165717D01*
X481139Y-167760D01*
X481357Y-170676D01*
X481139Y-173593D01*
X480266Y-175635D01*
X479174Y-177385D01*
X477864Y-178551D01*
X476117Y-179426D01*
X471751D01*
G01X17244Y226378D02*
Y246063D01*
G01X29055D02*
Y226378D01*
G01X25118Y222441D02*
X21181D01*
G01Y250000D02*
X25118D01*
G01X17244Y226378D02*
G03X21181Y222441I3937J0D01*
G01X25118D02*
G03X29055Y226378I0J3937D01*
G01Y246063D02*
G03X25118Y250000I-3937J0D01*
G01X21181D02*
G03X17244Y246063I0J-3937D01*
G01Y706693D02*
Y726378D01*
G01X29055D02*
Y706693D01*
G01X25118Y702756D02*
X21181D01*
G01Y730315D02*
X25118D01*
G01X17244Y706693D02*
G03X21181Y702756I3937J0D01*
G01X25118D02*
G03X29055Y706693I0J3937D01*
G01Y726378D02*
G03X25118Y730315I-3937J0D01*
G01X21181D02*
G03X17244Y726378I0J-3937D01*
G01X93694Y-19685D02*
X1317968D01*
G01X93694D02*
G03X85820I-3937J0D01*
G01X107993Y-7874D02*
X304843D01*
G01X107993Y0D02*
G03Y-7874I0J-3937D01*
G01X77283D02*
G03Y0I0J3937D01*
G01X107993Y480315D02*
G03Y472441I0J-3937D01*
G01X77283D02*
G03Y480315I0J3937D01*
G01X107993Y960630D02*
G03Y952756I0J-3937D01*
G01X77283D02*
G03Y960630I0J3937D01*
G01X107993D02*
X304843D01*
G01X208377Y-134426D02*
Y-116926D01*
X214054Y-131509D01*
X219731Y-116926D01*
Y-134426D01*
G01X231554D02*
X230244Y-134134D01*
X228934Y-132968D01*
X228060Y-130926D01*
X227624Y-128593D01*
X228060Y-126259D01*
X228934Y-124218D01*
X230244Y-123051D01*
X231554Y-122760D01*
X232864Y-123051D01*
X234174Y-124218D01*
X235047Y-126259D01*
X235266Y-128593D01*
X235047Y-130926D01*
X234174Y-132968D01*
X232864Y-134134D01*
X231554Y-134426D01*
G01X252984Y-116926D02*
Y-134426D01*
G01Y-131802D02*
X252111Y-133260D01*
X250800Y-134134D01*
X249272Y-134426D01*
X247526Y-133843D01*
X246216Y-132385D01*
X245342Y-130635D01*
X245124Y-128593D01*
X245342Y-126551D01*
X246216Y-124801D01*
X247526Y-123343D01*
X249272Y-122760D01*
X250800Y-123051D01*
X251892Y-123635D01*
X252984Y-124801D01*
G01X263279Y-126551D02*
X270266D01*
X269611Y-124509D01*
X268519Y-123343D01*
X266991Y-122760D01*
X265462Y-123051D01*
X264152Y-123926D01*
X263279Y-125968D01*
X262842Y-127718D01*
Y-129468D01*
X263279Y-131218D01*
X264371Y-132968D01*
X265681Y-134134D01*
X267209Y-134426D01*
X268737Y-133843D01*
X270266Y-132093D01*
G01X284054Y-134426D02*
Y-116926D01*
G01X335552Y-7874D02*
X532402D01*
G01X304843D02*
G03Y0I0J3937D01*
G01X335552D02*
G03Y-7874I0J-3937D01*
G01Y480315D02*
G03Y472441I0J-3937D01*
G01X304843D02*
G03Y480315I0J3937D01*
G01Y952756D02*
G03Y960630I0J3937D01*
G01X335552D02*
G03Y952756I0J-3937D01*
G01Y960630D02*
X532402D01*
G01X536554Y-179426D02*
Y-161926D01*
X533934Y-165426D01*
G01Y-179426D02*
X539174D01*
G01X549906Y-164843D02*
X551216Y-163093D01*
X552744Y-162218D01*
X554491Y-161926D01*
X556674Y-162509D01*
X558202Y-163968D01*
X558639Y-165717D01*
X558421Y-167468D01*
X557547Y-168926D01*
X553181Y-171843D01*
X551216Y-173884D01*
X549906Y-176802D01*
X549469Y-179426D01*
X558639D01*
G01X566751Y-176802D02*
X568060Y-178260D01*
X569589Y-179134D01*
X571554Y-179426D01*
X573519Y-178843D01*
X575047Y-177676D01*
X576139Y-175635D01*
X576357Y-173301D01*
X575921Y-170968D01*
X574829Y-169509D01*
X573300Y-168343D01*
X571772Y-168051D01*
X570244Y-168343D01*
X568279Y-169509D01*
X568934Y-161926D01*
X574829D01*
G01X584906Y-164843D02*
X586216Y-163093D01*
X587744Y-162218D01*
X589491Y-161926D01*
X591674Y-162509D01*
X593202Y-163968D01*
X593639Y-165717D01*
X593421Y-167468D01*
X592547Y-168926D01*
X588181Y-171843D01*
X586216Y-173884D01*
X584906Y-176802D01*
X584469Y-179426D01*
X593639D01*
G01X601751Y-175926D02*
X603060Y-177968D01*
X604807Y-179134D01*
X606772Y-179426D01*
X608519Y-179134D01*
X610266Y-177676D01*
X611357Y-175926D01*
X611576Y-174176D01*
X611139Y-172135D01*
X609611Y-170676D01*
X608082Y-170093D01*
X606117D01*
G01X608082D02*
X609392Y-169218D01*
X610484Y-167760D01*
X610921Y-166010D01*
X610484Y-164259D01*
X609392Y-162801D01*
X607427Y-161926D01*
X605462Y-162218D01*
X603497Y-163385D01*
G01X523437Y-134426D02*
Y-116926D01*
X528677D01*
X530424Y-117801D01*
X531734Y-119843D01*
X532171Y-122176D01*
X531734Y-124509D01*
X530642Y-126259D01*
X528677Y-127135D01*
X523437D01*
G01X550107Y-118385D02*
X548797Y-117509D01*
X547269Y-116926D01*
X545522D01*
X543557Y-117801D01*
X542029Y-119259D01*
X540937Y-121010D01*
X540064Y-123926D01*
X539845Y-126551D01*
X540282Y-129176D01*
X540937Y-130926D01*
X542247Y-132676D01*
X543776Y-133843D01*
X545304Y-134426D01*
X546832D01*
X548361Y-133843D01*
X549671Y-132968D01*
X550763Y-131802D01*
G01X564550Y-125093D02*
X565424Y-124218D01*
X566079Y-122760D01*
X566516Y-120717D01*
X566079Y-118968D01*
X565206Y-117801D01*
X563677Y-116926D01*
X557782D01*
Y-134426D01*
X564987D01*
X566516Y-133260D01*
X567389Y-131509D01*
X567826Y-129468D01*
X567389Y-127426D01*
X566079Y-125676D01*
X564550Y-125093D01*
X557782D01*
G01X573754Y-140259D02*
X586854D01*
G01X592782Y-134426D02*
Y-116926D01*
X602826Y-134426D01*
Y-116926D01*
G01X615304Y-134426D02*
X613557Y-134134D01*
X612029Y-132968D01*
X610719Y-131218D01*
X609845Y-129176D01*
X609409Y-126843D01*
Y-124509D01*
X609845Y-122176D01*
X610719Y-120134D01*
X612029Y-118385D01*
X613557Y-117218D01*
X615304Y-116926D01*
X617050Y-117218D01*
X618579Y-118385D01*
X619889Y-120134D01*
X620763Y-122176D01*
X621199Y-124509D01*
Y-126843D01*
X620763Y-129176D01*
X619889Y-131218D01*
X618579Y-132968D01*
X617050Y-134134D01*
X615304Y-134426D01*
G01X563111Y-7874D02*
X725552D01*
G01X563111Y0D02*
G03Y-7874I0J-3937D01*
G01X532402D02*
G03Y0I0J3937D01*
G01X627391Y353740D02*
X545906D01*
G01X627391D02*
X545906D01*
G01X627391Y378543D02*
X545906D01*
G01X627391D02*
X545906D01*
G01X541969Y357677D02*
Y374606D01*
G01Y357677D02*
Y374606D01*
G01X545906Y378543D02*
G03X541969Y374606I0J-3937D01*
G01Y357677D02*
G03X545906Y353740I3937J0D01*
G01X541969Y357677D02*
G03X545906Y353740I3937J0D01*
G01Y378543D02*
G03X541969Y374606I0J-3937D01*
G01X563111Y480315D02*
G03Y472441I0J-3937D01*
G01X532402D02*
G03Y480315I0J3937D01*
G01X627391Y834055D02*
X545906D01*
G01X627391D02*
X545906D01*
G01X541969Y837992D02*
Y854921D01*
G01Y837992D02*
Y854921D01*
G01Y837992D02*
G03X545906Y834055I3937J0D01*
G01X541969Y837992D02*
G03X545906Y834055I3937J0D01*
G01X627391Y858858D02*
X545906D01*
G01X627391D02*
X545906D01*
G01D02*
G03X541969Y854921I0J-3937D01*
G01X545906Y858858D02*
G03X541969Y854921I0J-3937D01*
G01X563111Y960630D02*
G03Y952756I0J-3937D01*
G01X532402D02*
G03Y960630I0J3937D01*
G01X563111D02*
X725552D01*
G01X636457Y132035D02*
X624646D01*
G01X636457D02*
X624646D01*
G01X620709Y135972D02*
Y312846D01*
G01Y135972D02*
Y312846D01*
G01Y135972D02*
G03X622708Y132545I3937J0D01*
G01X620709Y135972D02*
G03X622675Y132564I3937J0D01*
G01X622708Y132545D02*
G03X624646Y132035I1938J3427D01*
G01X622675Y132564D02*
G03X624646Y132035I1971J3409D01*
G01X620709Y135972D02*
Y312846D01*
G01Y135972D02*
Y312846D01*
G01Y135972D02*
G03X622708Y132545I3937J0D01*
G01X620709Y135972D02*
G03X622675Y132564I3937J0D01*
G01D02*
G03X624646Y132035I1971J3409D01*
G01X620709Y312657D02*
Y311161D01*
G01X636457Y316783D02*
X624646D01*
G01X636457D02*
X624646D01*
G01X622708Y316274D02*
G03X620709Y312846I1938J-3427D01*
G01X622675Y316255D02*
G03X620709Y312846I1971J-3408D01*
G01X624646Y316783D02*
G03X622708Y316274I-2J-3937D01*
G01X624646Y316783D02*
G03X622675Y316255I-1J-3937D01*
G01X622708Y316274D02*
G03X620709Y312846I1938J-3427D01*
G01X622675Y316255D02*
G03X620709Y312846I1971J-3408D01*
G01X624646Y316783D02*
G03X622675Y316255I-1J-3937D01*
G01X629574Y379204D02*
X638641Y385248D01*
G01X629574Y379204D02*
X638641Y385248D01*
G01Y347035D02*
X629574Y353079D01*
G01X638641Y347035D02*
X629574Y353079D01*
G01D02*
G03X627391Y353740I-2183J-3276D01*
G01X629574Y353079D02*
G03X627391Y353740I-2183J-3276D01*
G01Y378543D02*
G03X629574Y379205I-2J3937D01*
G01X627391Y378543D02*
G03X629574Y379205I-2J3937D01*
G01X636457Y612350D02*
X624646D01*
G01X636457D02*
X624646D01*
G01X620709Y616287D02*
Y793161D01*
G01Y616287D02*
Y793161D01*
G01Y616287D02*
G03X622708Y612860I3937J0D01*
G01X620709Y616287D02*
G03X622675Y612879I3937J0D01*
G01X622708Y612860D02*
G03X624646Y612350I1938J3427D01*
G01X622675Y612879D02*
G03X624646Y612350I1971J3409D01*
G01X638641Y827350D02*
X629574Y833394D01*
G01X638641Y827350D02*
X629574Y833394D01*
G01D02*
G03X627391Y834055I-2184J-3276D01*
G01X629574Y833394D02*
G03X627391Y834055I-2184J-3276D01*
G01X636457Y797098D02*
X624646D01*
G01X636457D02*
X624646D01*
G01X622708Y796589D02*
G03X620709Y793161I1938J-3427D01*
G01X622675Y796570D02*
G03X620709Y793161I1971J-3408D01*
G01X624646Y797098D02*
G03X622708Y796589I-2J-3937D01*
G01X624646Y797098D02*
G03X622675Y796570I-1J-3937D01*
G01X629574Y859520D02*
X638641Y865563D01*
G01X629574Y859520D02*
X638641Y865563D01*
G01X627391Y858858D02*
G03X629574Y859520I-2J3937D01*
G01X627391Y858858D02*
G03X629574Y859520I-2J3937D01*
G01X697854Y-179426D02*
Y-161926D01*
X695234Y-165426D01*
G01Y-179426D02*
X700474D01*
G01X666145Y-116926D02*
X671604Y-134426D01*
X677063Y-116926D01*
G01X693471Y-134426D02*
X684737D01*
Y-116926D01*
X693471D01*
G01X689977Y-125384D02*
X684737D01*
G01X702237Y-134426D02*
Y-116926D01*
X707696D01*
X709442Y-117801D01*
X710534Y-118968D01*
X710971Y-121301D01*
X710534Y-123635D01*
X709224Y-125093D01*
X707696Y-125968D01*
X702237D01*
G01X707696D02*
X710971Y-134426D01*
G01X724104Y-135009D02*
X723667Y-134718D01*
Y-134134D01*
X724104Y-133843D01*
X724541Y-134134D01*
Y-134718D01*
X724104Y-135009D01*
G01X640394Y112350D02*
Y3937D01*
G01Y112350D02*
Y3937D01*
G01X636457Y0D02*
G03X640394Y3937I0J3937D01*
G01X636457Y0D02*
G03X640394Y3937I0J3937D01*
G01X1284723Y0D02*
X652203D01*
G01X1284723D02*
X652203D01*
G01X648266Y3937D02*
Y83917D01*
G01Y3937D02*
Y83917D01*
G01Y3937D02*
G03X652203Y0I3937J0D01*
G01X648266Y3937D02*
G03X652203Y0I3937J0D01*
G01X648267Y34437D02*
G03X640393I-3937J0D01*
G01X640394Y128098D02*
Y3937D01*
G01Y128098D02*
Y3937D01*
G01X659085Y93237D02*
X650019Y87193D01*
G01X659085Y93237D02*
X650019Y87193D01*
G01X661269Y93898D02*
X742754D01*
G01X661269D02*
X742754D01*
G01X650019Y87193D02*
G03X648266Y83917I2185J-3276D01*
G01X661269Y93898D02*
G03X659085Y93237I0J-3937D01*
G01X661269Y93898D02*
G03X659085Y93237I0J-3937D01*
G01X650019Y87193D02*
G03X648266Y83917I2185J-3276D01*
G01X640393Y65146D02*
G03X648267I3937J0D01*
G01X661269Y118701D02*
X742754D01*
G01X661269D02*
X742754D01*
G01X650019Y125406D02*
X659085Y119362D01*
G01X650019Y125406D02*
X659085Y119362D01*
G01D02*
G03X661269Y118701I2184J3276D01*
G01X648266Y128682D02*
G03X650019Y125406I3937J0D01*
G01X648266Y128682D02*
G03X650019Y125406I3937J0D01*
G01X659085Y119362D02*
G03X661269Y118701I2184J3276D01*
G01X640394Y128098D02*
G03X636457Y132035I-3937J0D01*
G01X640394Y128098D02*
G03X636457Y132035I-3937J0D01*
G01X652203Y155657D02*
X664014D01*
G01X652203D02*
X664014D01*
G01X667951Y336469D02*
Y159594D01*
G01Y336469D02*
Y159594D01*
G01X648266Y128682D02*
Y151720D01*
G01Y128682D02*
Y151720D01*
G01X665952Y156167D02*
G03X667951Y159594I-1938J3427D01*
G01X665985Y156186D02*
G03X667951Y159594I-1971J3408D01*
G01X664014Y155657D02*
G03X665952Y156167I0J3937D01*
G01X652203Y155657D02*
G03X648266Y151720I0J-3937D01*
G01X652203Y155657D02*
G03X648266Y151720I0J-3937D01*
G01X664014Y155657D02*
G03X665985Y156186I0J3938D01*
G01X640394Y343759D02*
Y320720D01*
G01Y343759D02*
Y320720D01*
G01X636457Y316783D02*
G03X640394Y320720I0J3937D01*
G01X636457Y316783D02*
G03X640394Y320720I0J3937D01*
G01Y468504D02*
Y388524D01*
G01Y468504D02*
Y388524D01*
G01Y343759D02*
G03X638641Y347035I-3938J0D01*
G01X640394Y343759D02*
G03X638641Y347035I-3938J0D01*
G01Y385248D02*
G03X640394Y388524I-2185J3276D01*
G01X638641Y385248D02*
G03X640394Y388524I-2185J3276D01*
G01X648266Y360091D02*
Y468504D01*
G01Y360091D02*
Y468504D01*
G01X652203Y340406D02*
X664014D01*
G01X652203D02*
X664014D01*
G01X648266Y344343D02*
Y468504D01*
G01Y344343D02*
Y468504D01*
G01X667951Y336469D02*
G03X665952Y339896I-3937J0D01*
G01X667951Y336469D02*
G03X665985Y339877I-3937J0D01*
G01X648266Y344343D02*
G03X652203Y340406I3937J0D01*
G01X665952Y339896D02*
G03X664014Y340406I-1938J-3427D01*
G01X648266Y344343D02*
G03X652203Y340406I3937J0D01*
G01X665985Y339877D02*
G03X664014Y340406I-1971J-3409D01*
G01X648267Y407295D02*
G03X640393I-3937J0D01*
G01Y438004D02*
G03X648267I3937J0D01*
G01X640394Y468504D02*
G03X636457Y472441I-3937J0D01*
G01X640394Y468504D02*
G03X636457Y472441I-3937J0D01*
G01X640394Y592665D02*
Y484252D01*
G01Y592665D02*
Y484252D01*
G01X636457Y480315D02*
G03X640394Y484252I0J3937D01*
G01X636457Y480315D02*
G03X640394Y484252I0J3937D01*
G01X1284723Y480315D02*
X652203D01*
G01X1284723D02*
X652203D01*
G01X648266Y484252D02*
Y564231D01*
G01Y484252D02*
Y564231D01*
G01Y484252D02*
G03X652203Y480315I3937J0D01*
G01X648266Y484252D02*
G03X652203Y480315I3937J0D01*
G01Y472441D02*
X1284723D01*
G01X652203D02*
X1284723D01*
G01X652203D02*
G03X648266Y468504I0J-3937D01*
G01X652203Y472441D02*
G03X648266Y468504I0J-3937D01*
G01X640394Y608413D02*
Y484252D01*
G01Y608413D02*
Y484252D01*
G01X640393Y545462D02*
G03X648267I3937J0D01*
G01Y514753D02*
G03X640393I-3937J0D01*
G01X659085Y573552D02*
X650019Y567507D01*
G01X659085Y573552D02*
X650019Y567507D01*
G01X661269Y599016D02*
X742754D01*
G01X661269D02*
X742754D01*
G01X661269Y574213D02*
X742754D01*
G01X661269D02*
X742754D01*
G01X650019Y605721D02*
X659085Y599677D01*
G01X650019Y605721D02*
X659085Y599677D01*
G01D02*
G03X661269Y599016I2184J3276D01*
G01X648266Y608997D02*
G03X650019Y605721I3937J0D01*
G01X648266Y608997D02*
G03X650019Y605721I3937J0D01*
G01X659085Y599677D02*
G03X661269Y599016I2184J3276D01*
G01X650019Y567507D02*
G03X648266Y564231I2184J-3276D01*
G01X661269Y574213D02*
G03X659085Y573552I0J-3937D01*
G01X661269Y574213D02*
G03X659085Y573552I0J-3937D01*
G01X650019Y567507D02*
G03X648266Y564231I2184J-3276D01*
G01X640394Y608413D02*
G03X636457Y612350I-3937J0D01*
G01X640394Y608413D02*
G03X636457Y612350I-3937J0D01*
G01X648266Y608997D02*
Y632035D01*
G01Y608997D02*
Y632035D01*
G01X652203Y635972D02*
X664014D01*
G01X652203D02*
X664014D01*
G01X667951Y816783D02*
Y639909D01*
G01Y816783D02*
Y639909D01*
G01X665952Y636482D02*
G03X667951Y639909I-1938J3427D01*
G01X665985Y636501D02*
G03X667951Y639909I-1971J3408D01*
G01X664014Y635972D02*
G03X665952Y636482I0J3937D01*
G01X652203Y635972D02*
G03X648266Y632035I0J-3937D01*
G01X652203Y635972D02*
G03X648266Y632035I0J-3937D01*
G01X664014Y635972D02*
G03X665985Y636501I0J3938D01*
G01X640394Y824074D02*
G03X638641Y827350I-3938J0D01*
G01X640394Y824074D02*
G03X638641Y827350I-3938J0D01*
G01X648266Y840406D02*
Y948819D01*
G01Y840406D02*
Y948819D01*
G01X640394Y824074D02*
Y801035D01*
G01Y824074D02*
Y801035D01*
G01X636457Y797098D02*
G03X640394Y801035I0J3937D01*
G01X636457Y797098D02*
G03X640394Y801035I0J3937D01*
G01X652203Y820720D02*
X664014D01*
G01X652203D02*
X664014D01*
G01X648266Y824657D02*
Y948819D01*
G01Y824657D02*
Y948819D01*
G01X667951Y816783D02*
G03X665952Y820211I-3937J1D01*
G01X667951Y816783D02*
G03X665985Y820192I-3937J1D01*
G01X648266Y824657D02*
G03X652203Y820720I3937J0D01*
G01X665952Y820211D02*
G03X664014Y820720I-1936J-3428D01*
G01X648266Y824657D02*
G03X652203Y820720I3937J0D01*
G01X665985Y820192D02*
G03X664014Y820720I-1970J-3409D01*
G01X640394Y948819D02*
Y868839D01*
G01Y948819D02*
Y868839D01*
G01X638641Y865563D02*
G03X640394Y868839I-2185J3276D01*
G01X638641Y865563D02*
G03X640394Y868839I-2185J3276D01*
G01X648267Y887611D02*
G03X640393I-3937J0D01*
G01X640394Y948819D02*
G03X636457Y952756I-3937J0D01*
G01X640394Y948819D02*
G03X636457Y952756I-3937J0D01*
G01X652203D02*
X1284723D01*
G01X652203D02*
X1284723D01*
G01X652203D02*
G03X648266Y948819I0J-3937D01*
G01X652203Y952756D02*
G03X648266Y948819I0J-3937D01*
G01X640393Y918320D02*
G03X648267I3937J0D01*
G01X725552Y-7874D02*
G03Y0I0J3937D01*
G01X746691Y114764D02*
Y97835D01*
G01Y114764D02*
Y97835D01*
G01X742754Y93898D02*
G03X746691Y97835I0J3937D01*
G01X742754Y93898D02*
G03X746691Y97835I0J3937D01*
G01Y114764D02*
G03X742754Y118701I-3937J0D01*
G01X746691Y114764D02*
G03X742754Y118701I-3937J0D01*
G01X725552Y472441D02*
G03Y480315I0J3937D01*
G01X746691Y595079D02*
Y578150D01*
G01Y595079D02*
Y578150D01*
G01X742754Y574213D02*
G03X746691Y578150I0J3937D01*
G01Y595079D02*
G03X742754Y599016I-3937J0D01*
G01X746691Y595079D02*
G03X742754Y599016I-3937J0D01*
G01Y574213D02*
G03X746691Y578150I0J3937D01*
G01X725552Y952756D02*
G03Y960630I0J3937D01*
G01X799251Y-179426D02*
Y-161926D01*
X803617D01*
X805364Y-162801D01*
X806674Y-163968D01*
X807766Y-165717D01*
X808639Y-167760D01*
X808857Y-170676D01*
X808639Y-173593D01*
X807766Y-175635D01*
X806674Y-177385D01*
X805364Y-178551D01*
X803617Y-179426D01*
X799251D01*
G01X817187D02*
Y-161926D01*
X822646D01*
X824392Y-162801D01*
X825484Y-163968D01*
X825921Y-166301D01*
X825484Y-168635D01*
X824174Y-170093D01*
X822646Y-170968D01*
X817187D01*
G01X822646D02*
X825921Y-179426D01*
G01X836434Y-161926D02*
X841674D01*
G01X839054D02*
Y-179426D01*
G01X836434D02*
X841674D01*
G01X852187Y-161926D02*
Y-179426D01*
X860921D01*
G01X869687Y-161926D02*
Y-179426D01*
X878421D01*
G01X790937Y-116926D02*
Y-134426D01*
X799671D01*
G01X816734D02*
Y-122760D01*
G01Y-124801D02*
X815861Y-123635D01*
X814550Y-123051D01*
X813022Y-122760D01*
X811494Y-123343D01*
X810184Y-124509D01*
X809310Y-126259D01*
X808874Y-128593D01*
X809310Y-130926D01*
X810184Y-132676D01*
X811494Y-133843D01*
X813022Y-134426D01*
X814550Y-134134D01*
X815861Y-133260D01*
X816734Y-132093D01*
G01X825719Y-139676D02*
X827029Y-140259D01*
X828776Y-139676D01*
X829867Y-138510D01*
X830741Y-137051D01*
X832050Y-132385D01*
X834889Y-122760D01*
G01X827902D02*
X832050Y-132385D01*
G01X844529Y-126551D02*
X851516D01*
X850861Y-124509D01*
X849769Y-123343D01*
X848241Y-122760D01*
X846712Y-123051D01*
X845402Y-123926D01*
X844529Y-125968D01*
X844092Y-127718D01*
Y-129468D01*
X844529Y-131218D01*
X845621Y-132968D01*
X846931Y-134134D01*
X848459Y-134426D01*
X849987Y-133843D01*
X851516Y-132093D01*
G01X862247Y-134426D02*
Y-122760D01*
G01Y-125093D02*
X863339Y-123926D01*
X864431Y-123051D01*
X865959Y-122760D01*
X867050Y-123051D01*
X868361Y-123926D01*
G01X879529Y-132385D02*
X880621Y-133551D01*
X882149Y-134426D01*
X883459D01*
X884769Y-133843D01*
X885642Y-132968D01*
X886079Y-131802D01*
X885861Y-130051D01*
X884987Y-129176D01*
X881057Y-127426D01*
X880184Y-125384D01*
X880621Y-123926D01*
X881494Y-123051D01*
X882804Y-122760D01*
X884114Y-123051D01*
X885424Y-123926D01*
G01X756261Y0D02*
G03Y-7874I0J-3937D01*
G01X953111D02*
X756261D01*
G01Y480315D02*
G03Y472441I0J-3937D01*
G01Y960630D02*
G03Y952756I0J-3937D01*
G01X953111Y960630D02*
X756261D01*
G01X924737Y-175926D02*
X925829Y-177676D01*
X927139Y-178843D01*
X928667Y-179426D01*
X930414Y-178843D01*
X931724Y-177676D01*
X933034Y-175926D01*
X933471Y-173593D01*
Y-161926D01*
G01X946604Y-179426D02*
X944857Y-179134D01*
X943329Y-177968D01*
X942019Y-176218D01*
X941145Y-174176D01*
X940709Y-171843D01*
Y-169509D01*
X941145Y-167176D01*
X942019Y-165134D01*
X943329Y-163385D01*
X944857Y-162218D01*
X946604Y-161926D01*
X948350Y-162218D01*
X949879Y-163385D01*
X951189Y-165134D01*
X952063Y-167176D01*
X952499Y-169509D01*
Y-171843D01*
X952063Y-174176D01*
X951189Y-176218D01*
X949879Y-177968D01*
X948350Y-179134D01*
X946604Y-179426D01*
G01X959519Y-177093D02*
X961266Y-178551D01*
X963231Y-179426D01*
X964977D01*
X966724Y-178551D01*
X968034Y-177093D01*
X968689Y-175051D01*
X968252Y-173010D01*
X967161Y-171259D01*
X965196Y-170093D01*
X962576Y-169509D01*
X961047Y-168343D01*
X960392Y-166301D01*
X960829Y-164259D01*
X961921Y-162801D01*
X963449Y-161926D01*
X964977D01*
X966506Y-162509D01*
X967816Y-163968D01*
G01X985971Y-179426D02*
X977237D01*
Y-161926D01*
X985971D01*
G01X982477Y-170384D02*
X977237D01*
G01X994737Y-179426D02*
Y-161926D01*
X999977D01*
X1001724Y-162801D01*
X1003034Y-164843D01*
X1003471Y-167176D01*
X1003034Y-169509D01*
X1001942Y-171259D01*
X999977Y-172135D01*
X994737D01*
G01X1012019Y-179426D02*
Y-161926D01*
G01X1021189D02*
Y-179426D01*
G01Y-170676D02*
X1012019D01*
G01X1047237Y-161926D02*
Y-179426D01*
X1055971D01*
G01X1063645D02*
X1069104Y-161926D01*
X1074563Y-179426D01*
G01X1072597Y-173301D02*
X1065610D01*
G01X1081801Y-161926D02*
Y-174468D01*
X1082674Y-177093D01*
X1084421Y-178843D01*
X1086604Y-179426D01*
X1088787Y-178843D01*
X1090534Y-177093D01*
X1091407Y-174468D01*
Y-161926D01*
G01X941801Y-134426D02*
Y-116926D01*
X946167D01*
X947914Y-117801D01*
X949224Y-118968D01*
X950316Y-120717D01*
X951189Y-122760D01*
X951407Y-125676D01*
X951189Y-128593D01*
X950316Y-130635D01*
X949224Y-132385D01*
X947914Y-133551D01*
X946167Y-134426D01*
X941801D01*
G01X960829Y-126551D02*
X967816D01*
X967161Y-124509D01*
X966069Y-123343D01*
X964541Y-122760D01*
X963012Y-123051D01*
X961702Y-123926D01*
X960829Y-125968D01*
X960392Y-127718D01*
Y-129468D01*
X960829Y-131218D01*
X961921Y-132968D01*
X963231Y-134134D01*
X964759Y-134426D01*
X966287Y-133843D01*
X967816Y-132093D01*
G01X978329Y-132385D02*
X979421Y-133551D01*
X980949Y-134426D01*
X982259D01*
X983569Y-133843D01*
X984442Y-132968D01*
X984879Y-131802D01*
X984661Y-130051D01*
X983787Y-129176D01*
X979857Y-127426D01*
X978984Y-125384D01*
X979421Y-123926D01*
X980294Y-123051D01*
X981604Y-122760D01*
X982914Y-123051D01*
X984224Y-123926D01*
G01X999104Y-122760D02*
Y-134426D01*
G01Y-118093D02*
X998667Y-117801D01*
Y-117218D01*
X999104Y-116926D01*
X999541Y-117218D01*
Y-117801D01*
X999104Y-118093D01*
G01X1013547Y-138801D02*
X1015076Y-139968D01*
X1016822Y-140259D01*
X1018350Y-139968D01*
X1019661Y-138510D01*
X1020534Y-136468D01*
Y-122760D01*
G01Y-125093D02*
X1019661Y-123926D01*
X1018350Y-123051D01*
X1016822Y-122760D01*
X1015076Y-123343D01*
X1013984Y-124509D01*
X1013110Y-126551D01*
X1012674Y-128593D01*
X1012892Y-130343D01*
X1013766Y-132385D01*
X1015076Y-133843D01*
X1016822Y-134426D01*
X1018132Y-134134D01*
X1019661Y-132968D01*
X1020534Y-131802D01*
G01X1030392Y-134426D02*
Y-122760D01*
G01Y-125676D02*
X1031266Y-124218D01*
X1032576Y-123051D01*
X1034322Y-122760D01*
X1035850Y-123051D01*
X1037161Y-124218D01*
X1037816Y-126259D01*
Y-134426D01*
G01X1048329Y-126551D02*
X1055316D01*
X1054661Y-124509D01*
X1053569Y-123343D01*
X1052041Y-122760D01*
X1050512Y-123051D01*
X1049202Y-123926D01*
X1048329Y-125968D01*
X1047892Y-127718D01*
Y-129468D01*
X1048329Y-131218D01*
X1049421Y-132968D01*
X1050731Y-134134D01*
X1052259Y-134426D01*
X1053787Y-133843D01*
X1055316Y-132093D01*
G01X1066047Y-134426D02*
Y-122760D01*
G01Y-125093D02*
X1067139Y-123926D01*
X1068231Y-123051D01*
X1069759Y-122760D01*
X1070850Y-123051D01*
X1072161Y-123926D01*
G01X953111Y-7874D02*
G03Y0I0J3937D01*
G01Y472441D02*
G03Y480315I0J3937D01*
G01Y952756D02*
G03Y960630I0J3937D01*
G01X983820Y0D02*
G03Y-7874I0J-3937D01*
G01X1180670D02*
X983820D01*
G01Y480315D02*
G03Y472441I0J-3937D01*
G01Y960630D02*
G03Y952756I0J-3937D01*
G01X1180670Y960630D02*
X983820D01*
G01X1112804Y-179426D02*
Y-161926D01*
X1110184Y-165426D01*
G01Y-179426D02*
X1115424D01*
G01X1130304Y-161926D02*
X1128557Y-162509D01*
X1127247Y-163968D01*
X1126374Y-165717D01*
X1125719Y-168051D01*
X1125501Y-170676D01*
X1125719Y-173301D01*
X1126374Y-175635D01*
X1127247Y-177385D01*
X1128557Y-178843D01*
X1130304Y-179426D01*
X1132050Y-178843D01*
X1133361Y-177385D01*
X1134234Y-175635D01*
X1134889Y-173301D01*
X1135107Y-170676D01*
X1134889Y-168051D01*
X1134234Y-165717D01*
X1133361Y-163968D01*
X1132050Y-162509D01*
X1130304Y-161926D01*
G01X1143874Y-180009D02*
X1151734Y-161926D01*
G01X1165304Y-179426D02*
Y-161926D01*
X1162684Y-165426D01*
G01Y-179426D02*
X1167924D01*
G01X1179092Y-177385D02*
X1180621Y-178843D01*
X1182367Y-179426D01*
X1184114Y-178843D01*
X1185642Y-177093D01*
X1186734Y-174468D01*
X1187171Y-171843D01*
Y-168635D01*
X1186734Y-166010D01*
X1185642Y-163676D01*
X1184332Y-162509D01*
X1182804Y-161926D01*
X1181057Y-162509D01*
X1179747Y-163676D01*
X1178874Y-165426D01*
X1178437Y-167760D01*
X1178874Y-169801D01*
X1179966Y-171843D01*
X1181276Y-173010D01*
X1182804Y-173301D01*
X1184550Y-172718D01*
X1185861Y-171259D01*
X1187171Y-168635D01*
G01X1196374Y-180009D02*
X1204234Y-161926D01*
G01X1213656Y-164843D02*
X1214966Y-163093D01*
X1216494Y-162218D01*
X1218241Y-161926D01*
X1220424Y-162509D01*
X1221952Y-163968D01*
X1222389Y-165717D01*
X1222171Y-167468D01*
X1221297Y-168926D01*
X1216931Y-171843D01*
X1214966Y-173884D01*
X1213656Y-176802D01*
X1213219Y-179426D01*
X1222389D01*
G01X1235304Y-161926D02*
X1233557Y-162509D01*
X1232247Y-163968D01*
X1231374Y-165717D01*
X1230719Y-168051D01*
X1230501Y-170676D01*
X1230719Y-173301D01*
X1231374Y-175635D01*
X1232247Y-177385D01*
X1233557Y-178843D01*
X1235304Y-179426D01*
X1237050Y-178843D01*
X1238361Y-177385D01*
X1239234Y-175635D01*
X1239889Y-173301D01*
X1240107Y-170676D01*
X1239889Y-168051D01*
X1239234Y-165717D01*
X1238361Y-163968D01*
X1237050Y-162509D01*
X1235304Y-161926D01*
G01X1252804Y-179426D02*
Y-161926D01*
X1250184Y-165426D01*
G01Y-179426D02*
X1255424D01*
G01X1266156Y-164843D02*
X1267466Y-163093D01*
X1268994Y-162218D01*
X1270741Y-161926D01*
X1272924Y-162509D01*
X1274452Y-163968D01*
X1274889Y-165717D01*
X1274671Y-167468D01*
X1273797Y-168926D01*
X1269431Y-171843D01*
X1267466Y-173884D01*
X1266156Y-176802D01*
X1265719Y-179426D01*
X1274889D01*
G01X1160501Y-134426D02*
Y-116926D01*
X1164867D01*
X1166614Y-117801D01*
X1167924Y-118968D01*
X1169016Y-120717D01*
X1169889Y-122760D01*
X1170107Y-125676D01*
X1169889Y-128593D01*
X1169016Y-130635D01*
X1167924Y-132385D01*
X1166614Y-133551D01*
X1164867Y-134426D01*
X1160501D01*
G01X1186734D02*
Y-122760D01*
G01Y-124801D02*
X1185861Y-123635D01*
X1184550Y-123051D01*
X1183022Y-122760D01*
X1181494Y-123343D01*
X1180184Y-124509D01*
X1179310Y-126259D01*
X1178874Y-128593D01*
X1179310Y-130926D01*
X1180184Y-132676D01*
X1181494Y-133843D01*
X1183022Y-134426D01*
X1184550Y-134134D01*
X1185861Y-133260D01*
X1186734Y-132093D01*
G01X1200304Y-116926D02*
Y-134426D01*
G01X1197247Y-122760D02*
X1203361D01*
G01X1214529Y-126551D02*
X1221516D01*
X1220861Y-124509D01*
X1219769Y-123343D01*
X1218241Y-122760D01*
X1216712Y-123051D01*
X1215402Y-123926D01*
X1214529Y-125968D01*
X1214092Y-127718D01*
Y-129468D01*
X1214529Y-131218D01*
X1215621Y-132968D01*
X1216931Y-134134D01*
X1218459Y-134426D01*
X1219987Y-133843D01*
X1221516Y-132093D01*
G01X1180670Y-7874D02*
G03Y0I0J3937D01*
G01Y472441D02*
G03Y480315I0J3937D01*
G01Y952756D02*
G03Y960630I0J3937D01*
G01X1211380Y-7874D02*
X1284723D01*
G01X1211380Y0D02*
G03Y-7874I0J-3937D01*
G01X1259605Y226378D02*
Y246063D01*
G01X1263542Y250000D02*
G03X1259605Y246063I0J-3937D01*
G01Y226378D02*
G03X1263542Y222441I3937J0D01*
G01X1211380Y480315D02*
G03Y472441I0J-3937D01*
G01X1259605Y706693D02*
Y726378D01*
G01X1263542Y730315D02*
G03X1259605Y726378I0J-3937D01*
G01Y706693D02*
G03X1263542Y702756I3937J0D01*
G01X1211380Y960630D02*
G03Y952756I0J-3937D01*
G01Y960630D02*
X1284723D01*
G01X1317968Y-19685D02*
G03X1331968Y-5685I0J14000D01*
G01X1288660Y102559D02*
Y3937D01*
G01Y102559D02*
Y3937D01*
G01X1284723Y0D02*
G03X1288660Y3937I0J3937D01*
G01X1284723Y0D02*
G03X1288660Y3937I0J3937D01*
G01X1284723Y-7874D02*
G03X1296534Y3937I0J11811D01*
G01D02*
Y45847D01*
G01D02*
G03X1288660I-3937J0D01*
G01X1292597Y106496D02*
G03X1288660Y102559I0J-3937D01*
G01X1292597Y106496D02*
G03X1288660Y102559I0J-3937D01*
G01X1331968Y98622D02*
X1296534D01*
G01D02*
Y71044D01*
G01X1288660D02*
G03X1296534I3937J0D01*
G01X1292597Y106496D02*
X1326061D01*
G01X1292597D02*
X1326061D01*
G01X1301258Y180394D02*
X1326061D01*
G01D02*
X1290038D01*
G01X1301258D02*
X1290038D01*
G01X1326061Y177638D02*
X1290038D01*
G01X1326061D02*
X1290038D01*
G01Y180394D02*
G03Y177638I0J-1378D01*
G01Y180394D02*
G03Y177638I0J-1378D01*
G01X1271416Y246063D02*
Y226378D01*
G01X1263542Y250000D02*
X1267479D01*
G01Y222441D02*
X1263542D01*
G01X1271416Y246063D02*
G03X1267479Y250000I-3937J0D01*
G01Y222441D02*
G03X1271416Y226378I0J3937D01*
G01X1288660Y468504D02*
Y365472D01*
G01Y468504D02*
Y365472D01*
G01X1326061Y361535D02*
X1292597D01*
G01X1326061D02*
X1292597D01*
G01X1288660Y365472D02*
G03X1292597Y361535I3937J0D01*
G01X1288660Y365472D02*
G03X1292597Y361535I3937J0D01*
G01X1331968Y369409D02*
X1296534D01*
G01D02*
Y396985D01*
G01D02*
G03X1288660I-3937J0D01*
G01X1296534Y526162D02*
Y422182D01*
G01X1288660D02*
G03X1296534I3937J0D01*
G01X1288660Y582874D02*
Y484252D01*
G01Y582874D02*
Y484252D01*
G01X1284723Y480315D02*
G03X1288660Y484252I0J3937D01*
G01X1284723Y480315D02*
G03X1288660Y484252I0J3937D01*
G01Y468504D02*
G03X1284723Y472441I-3937J0D01*
G01X1288660Y468504D02*
G03X1284723Y472441I-3937J0D01*
G01X1296534Y578937D02*
Y551359D01*
G01X1288660D02*
G03X1296534I3937J0D01*
G01Y526162D02*
G03X1288660I-3937J0D01*
G01X1292597Y586811D02*
X1326061D01*
G01X1292597D02*
X1326061D01*
G01X1292597D02*
G03X1288660Y582874I0J-3937D01*
G01X1292597Y586811D02*
G03X1288660Y582874I0J-3937D01*
G01X1331968Y578937D02*
X1296534D01*
G01X1301258Y660709D02*
X1326061D01*
G01D02*
X1290038D01*
G01X1301258D02*
X1290038D01*
G01X1326061Y657953D02*
X1290038D01*
G01X1326061D02*
X1290038D01*
G01Y660709D02*
G03Y657953I0J-1378D01*
G01Y660709D02*
G03Y657953I0J-1378D01*
G01X1271416Y726378D02*
Y706693D01*
G01X1263542Y730315D02*
X1267479D01*
G01Y702756D02*
X1263542D01*
G01X1271416Y726378D02*
G03X1267479Y730315I-3937J0D01*
G01Y702756D02*
G03X1271416Y706693I0J3937D01*
G01X1326061Y841850D02*
X1292597D01*
G01X1326061D02*
X1292597D01*
G01X1288660Y845787D02*
G03X1292597Y841850I3937J0D01*
G01X1288660Y845787D02*
G03X1292597Y841850I3937J0D01*
G01X1288660Y948819D02*
Y845787D01*
G01Y948819D02*
Y845787D01*
G01X1296534Y849724D02*
Y877300D01*
G01Y877296D02*
G03X1288660I-3937J0D01*
G01X1296534Y948819D02*
Y902497D01*
G01X1288660D02*
G03X1296534I3937J0D01*
G01X1331968Y849724D02*
X1296534D01*
G01X1288660Y948819D02*
G03X1284723Y952756I-3937J0D01*
G01X1288660Y948819D02*
G03X1284723Y952756I-3937J0D01*
G01X1296534Y948819D02*
G03X1284723Y960630I-11811J0D01*
G01X1331968Y958441D02*
G03X1317968Y972441I-14000J0D01*
G01X1331968Y-5685D02*
Y98622D01*
G01X1331967Y112402D02*
Y171732D01*
G01X1326061Y106496D02*
X1329998Y110433D01*
G01X1326061Y106496D02*
X1331967Y112402D01*
G01Y186299D02*
Y355630D01*
G01X1326061Y180394D02*
X1329998Y184331D01*
G01X1326061Y180394D02*
X1331967Y186299D01*
G01Y171732D02*
X1326061Y177638D01*
G01X1329998Y173701D02*
X1326061Y177638D01*
G01X1331967Y355630D02*
X1326061Y361535D01*
G01X1329998Y357598D02*
X1326061Y361535D01*
G01X1331968Y578937D02*
Y369409D01*
G01X1331967Y592717D02*
Y652047D01*
G01X1326061Y586811D02*
X1329998Y590748D01*
G01X1326061Y586811D02*
X1331967Y592717D01*
G01Y666614D02*
Y835945D01*
G01X1326061Y660709D02*
X1329998Y664646D01*
G01X1326061Y660709D02*
X1331967Y666614D01*
G01Y652047D02*
X1326061Y657953D01*
G01X1329998Y654016D02*
X1326061Y657953D01*
G01X1331967Y835945D02*
X1326061Y841850D01*
G01X1329998Y837913D02*
X1326061Y841850D01*
G01X1331968Y958441D02*
Y849724D01*
G01X1471085Y53500D02*
Y66000D01*
X1478215Y53500D01*
Y66000D01*
G01X1487050Y53500D02*
X1486120Y53708D01*
X1485190Y54541D01*
X1484570Y56000D01*
X1484260Y57667D01*
X1484570Y59333D01*
X1485190Y60792D01*
X1486120Y61625D01*
X1487050Y61833D01*
X1487980Y61625D01*
X1488910Y60792D01*
X1489530Y59333D01*
X1489685Y57667D01*
X1489530Y56000D01*
X1488910Y54541D01*
X1487980Y53708D01*
X1487050Y53500D01*
G01X1499450Y66000D02*
Y53500D01*
G01X1497280Y61833D02*
X1501620D01*
G01X1509525Y59125D02*
X1514485D01*
X1514020Y60583D01*
X1513245Y61417D01*
X1512160Y61833D01*
X1511075Y61625D01*
X1510145Y61000D01*
X1509525Y59542D01*
X1509215Y58291D01*
Y57042D01*
X1509525Y55792D01*
X1510300Y54541D01*
X1511230Y53708D01*
X1512315Y53500D01*
X1513400Y53917D01*
X1514485Y55166D01*
G01X1524250Y53083D02*
X1523940Y53292D01*
Y53708D01*
X1524250Y53917D01*
X1524560Y53708D01*
Y53292D01*
X1524250Y53083D01*
G01Y58708D02*
X1523940Y58917D01*
Y59333D01*
X1524250Y59542D01*
X1524560Y59333D01*
Y58917D01*
X1524250Y58708D01*
G01X1533550Y53500D02*
Y66000D01*
X1537425D01*
X1538665Y65375D01*
X1539440Y64542D01*
X1539750Y62875D01*
X1539440Y61208D01*
X1538510Y60167D01*
X1537425Y59542D01*
X1533550D01*
G01X1537425D02*
X1539750Y53500D01*
G01X1546725Y59125D02*
X1551685D01*
X1551220Y60583D01*
X1550445Y61417D01*
X1549360Y61833D01*
X1548275Y61625D01*
X1547345Y61000D01*
X1546725Y59542D01*
X1546415Y58291D01*
Y57042D01*
X1546725Y55792D01*
X1547500Y54541D01*
X1548430Y53708D01*
X1549515Y53500D01*
X1550600Y53917D01*
X1551685Y55166D01*
G01X1560520Y53500D02*
Y64125D01*
X1560830Y65166D01*
X1561450Y65792D01*
X1562380Y66000D01*
X1563310Y65583D01*
X1563775Y64542D01*
G01X1561915Y61000D02*
X1558815D01*
G01X1571525Y59125D02*
X1576485D01*
X1576020Y60583D01*
X1575245Y61417D01*
X1574160Y61833D01*
X1573075Y61625D01*
X1572145Y61000D01*
X1571525Y59542D01*
X1571215Y58291D01*
Y57042D01*
X1571525Y55792D01*
X1572300Y54541D01*
X1573230Y53708D01*
X1574315Y53500D01*
X1575400Y53917D01*
X1576485Y55166D01*
G01X1584080Y53500D02*
Y61833D01*
G01Y60167D02*
X1584855Y61000D01*
X1585630Y61625D01*
X1586715Y61833D01*
X1587490Y61625D01*
X1588420Y61000D01*
G01X1611050Y66000D02*
Y53500D01*
G01X1608880Y61833D02*
X1613220D01*
G01X1623450Y53500D02*
X1622520Y53708D01*
X1621590Y54541D01*
X1620970Y56000D01*
X1620660Y57667D01*
X1620970Y59333D01*
X1621590Y60792D01*
X1622520Y61625D01*
X1623450Y61833D01*
X1624380Y61625D01*
X1625310Y60792D01*
X1625930Y59333D01*
X1626085Y57667D01*
X1625930Y56000D01*
X1625310Y54541D01*
X1624380Y53708D01*
X1623450Y53500D01*
G01X1644840D02*
Y66000D01*
X1647940D01*
X1649180Y65375D01*
X1650110Y64542D01*
X1650885Y63292D01*
X1651505Y61833D01*
X1651660Y59750D01*
X1651505Y57667D01*
X1650885Y56208D01*
X1650110Y54958D01*
X1649180Y54125D01*
X1647940Y53500D01*
X1644840D01*
G01X1657550D02*
Y66000D01*
X1661425D01*
X1662665Y65375D01*
X1663440Y64542D01*
X1663750Y62875D01*
X1663440Y61208D01*
X1662510Y60167D01*
X1661425Y59542D01*
X1657550D01*
G01X1661425D02*
X1663750Y53500D01*
G01X1671190Y66000D02*
X1674910D01*
G01X1673050D02*
Y53500D01*
G01X1671190D02*
X1674910D01*
G01X1682350Y66000D02*
Y53500D01*
X1688550D01*
G01X1694750Y66000D02*
Y53500D01*
X1700950D01*
G01X1722650D02*
Y66000D01*
G01X1737840Y53500D02*
Y61833D01*
G01Y60375D02*
X1737220Y61208D01*
X1736290Y61625D01*
X1735205Y61833D01*
X1734120Y61417D01*
X1733190Y60583D01*
X1732570Y59333D01*
X1732260Y57667D01*
X1732570Y56000D01*
X1733190Y54750D01*
X1734120Y53917D01*
X1735205Y53500D01*
X1736290Y53708D01*
X1737220Y54333D01*
X1737840Y55166D01*
G01X1744195Y49750D02*
X1745125Y49333D01*
X1746365Y49750D01*
X1747140Y50583D01*
X1747760Y51625D01*
X1748690Y54958D01*
X1750705Y61833D01*
G01X1745745D02*
X1748690Y54958D01*
G01X1757525Y59125D02*
X1762485D01*
X1762020Y60583D01*
X1761245Y61417D01*
X1760160Y61833D01*
X1759075Y61625D01*
X1758145Y61000D01*
X1757525Y59542D01*
X1757215Y58291D01*
Y57042D01*
X1757525Y55792D01*
X1758300Y54541D01*
X1759230Y53708D01*
X1760315Y53500D01*
X1761400Y53917D01*
X1762485Y55166D01*
G01X1770080Y53500D02*
Y61833D01*
G01Y60167D02*
X1770855Y61000D01*
X1771630Y61625D01*
X1772715Y61833D01*
X1773490Y61625D01*
X1774420Y61000D01*
G01X1796120Y53500D02*
Y64125D01*
X1796430Y65166D01*
X1797050Y65792D01*
X1797980Y66000D01*
X1798910Y65583D01*
X1799375Y64542D01*
G01X1797515Y61000D02*
X1794415D01*
G01X1809450Y53500D02*
X1808520Y53708D01*
X1807590Y54541D01*
X1806970Y56000D01*
X1806660Y57667D01*
X1806970Y59333D01*
X1807590Y60792D01*
X1808520Y61625D01*
X1809450Y61833D01*
X1810380Y61625D01*
X1811310Y60792D01*
X1811930Y59333D01*
X1812085Y57667D01*
X1811930Y56000D01*
X1811310Y54541D01*
X1810380Y53708D01*
X1809450Y53500D01*
G01X1819680D02*
Y61833D01*
G01Y60167D02*
X1820455Y61000D01*
X1821230Y61625D01*
X1822315Y61833D01*
X1823090Y61625D01*
X1824020Y61000D01*
G01X1849750Y53500D02*
X1843550D01*
Y66000D01*
X1849750D01*
G01X1847270Y59958D02*
X1843550D01*
G01X1855950Y66000D02*
Y53500D01*
X1862150D01*
G01X1868350Y66000D02*
Y53500D01*
X1874550D01*
G01X1881990Y66000D02*
X1885710D01*
G01X1883850D02*
Y53500D01*
G01X1881990D02*
X1885710D01*
G01X1893150D02*
Y66000D01*
X1896870D01*
X1898110Y65375D01*
X1899040Y63917D01*
X1899350Y62250D01*
X1899040Y60583D01*
X1898265Y59333D01*
X1896870Y58708D01*
X1893150D01*
G01X1905395Y55166D02*
X1906635Y54125D01*
X1908030Y53500D01*
X1909270D01*
X1910510Y54125D01*
X1911440Y55166D01*
X1911905Y56625D01*
X1911595Y58083D01*
X1910820Y59333D01*
X1909425Y60167D01*
X1907565Y60583D01*
X1906480Y61417D01*
X1906015Y62875D01*
X1906325Y64333D01*
X1907100Y65375D01*
X1908185Y66000D01*
X1909270D01*
X1910355Y65583D01*
X1911285Y64542D01*
G01X1924150Y53500D02*
X1917950D01*
Y66000D01*
X1924150D01*
G01X1921670Y59958D02*
X1917950D01*
G01X1948640Y66000D02*
Y53500D01*
G01Y55375D02*
X1948020Y54333D01*
X1947090Y53708D01*
X1946005Y53500D01*
X1944765Y53917D01*
X1943835Y54958D01*
X1943215Y56208D01*
X1943060Y57667D01*
X1943215Y59125D01*
X1943835Y60375D01*
X1944765Y61417D01*
X1946005Y61833D01*
X1947090Y61625D01*
X1947865Y61208D01*
X1948640Y60375D01*
G01X1956080Y53500D02*
Y61833D01*
G01Y60167D02*
X1956855Y61000D01*
X1957630Y61625D01*
X1958715Y61833D01*
X1959490Y61625D01*
X1960420Y61000D01*
G01X1970650Y61833D02*
Y53500D01*
G01Y65166D02*
X1970340Y65375D01*
Y65792D01*
X1970650Y66000D01*
X1970960Y65792D01*
Y65375D01*
X1970650Y65166D01*
G01X1983050Y53500D02*
Y66000D01*
G01X1995450Y53500D02*
Y66000D01*
G01X2023040D02*
Y53500D01*
G01Y55375D02*
X2022420Y54333D01*
X2021490Y53708D01*
X2020405Y53500D01*
X2019165Y53917D01*
X2018235Y54958D01*
X2017615Y56208D01*
X2017460Y57667D01*
X2017615Y59125D01*
X2018235Y60375D01*
X2019165Y61417D01*
X2020405Y61833D01*
X2021490Y61625D01*
X2022265Y61208D01*
X2023040Y60375D01*
G01X2032650Y61833D02*
Y53500D01*
G01Y65166D02*
X2032340Y65375D01*
Y65792D01*
X2032650Y66000D01*
X2032960Y65792D01*
Y65375D01*
X2032650Y65166D01*
G01X2042880Y53500D02*
Y61833D01*
G01Y60167D02*
X2043655Y61000D01*
X2044430Y61625D01*
X2045515Y61833D01*
X2046290Y61625D01*
X2047220Y61000D01*
G01X2055125Y59125D02*
X2060085D01*
X2059620Y60583D01*
X2058845Y61417D01*
X2057760Y61833D01*
X2056675Y61625D01*
X2055745Y61000D01*
X2055125Y59542D01*
X2054815Y58291D01*
Y57042D01*
X2055125Y55792D01*
X2055900Y54541D01*
X2056830Y53708D01*
X2057915Y53500D01*
X2059000Y53917D01*
X2060085Y55166D01*
G01X2072330Y60792D02*
X2071245Y61625D01*
X2070315Y61833D01*
X2069075Y61417D01*
X2068145Y60583D01*
X2067525Y59125D01*
X2067370Y57667D01*
X2067525Y56208D01*
X2068145Y54958D01*
X2069075Y53917D01*
X2070315Y53500D01*
X2071400Y53917D01*
X2072330Y54750D01*
G01X2082250Y66000D02*
Y53500D01*
G01X2080080Y61833D02*
X2084420D01*
G01X2094650D02*
Y53500D01*
G01Y65166D02*
X2094340Y65375D01*
Y65792D01*
X2094650Y66000D01*
X2094960Y65792D01*
Y65375D01*
X2094650Y65166D01*
G01X2107050Y53500D02*
X2106120Y53708D01*
X2105190Y54541D01*
X2104570Y56000D01*
X2104260Y57667D01*
X2104570Y59333D01*
X2105190Y60792D01*
X2106120Y61625D01*
X2107050Y61833D01*
X2107980Y61625D01*
X2108910Y60792D01*
X2109530Y59333D01*
X2109685Y57667D01*
X2109530Y56000D01*
X2108910Y54541D01*
X2107980Y53708D01*
X2107050Y53500D01*
G01X2116815D02*
Y61833D01*
G01Y59750D02*
X2117435Y60792D01*
X2118365Y61625D01*
X2119605Y61833D01*
X2120690Y61625D01*
X2121620Y60792D01*
X2122085Y59333D01*
Y53500D01*
G01X1470000Y83500D02*
Y389500D01*
X1953600D01*
Y83500D01*
X1470000D01*
G01Y111600D02*
X1953600D01*
G01X1470000Y139700D02*
X1953600D01*
G01X1470000Y167800D02*
X1953600D01*
G01X1470000Y195900D02*
X1953600D01*
G01X1470000Y224000D02*
X1953600D01*
G01X1470000Y252100D02*
X1953600D01*
G01X1470000Y280200D02*
X1953600D01*
G01X1470000Y308300D02*
X1953600D01*
G01X1481005Y317650D02*
Y330150D01*
X1486895D01*
G01X1484725Y324108D02*
X1481005D01*
G01X1494490Y330150D02*
X1498210D01*
G01X1496350D02*
Y317650D01*
G01X1494490D02*
X1498210D01*
G01X1509680Y323900D02*
X1512780D01*
Y320150D01*
X1511850Y318900D01*
X1510765Y318067D01*
X1509215Y317650D01*
X1507665Y318067D01*
X1506580Y318900D01*
X1505650Y320150D01*
X1505030Y321608D01*
X1504720Y323275D01*
Y324733D01*
X1505030Y325983D01*
X1505650Y327442D01*
X1506580Y328692D01*
X1507510Y329525D01*
X1508750Y330150D01*
X1509835D01*
X1511075Y329733D01*
X1512005Y328900D01*
G01X1517740Y330150D02*
Y321192D01*
X1518360Y319316D01*
X1519600Y318067D01*
X1521150Y317650D01*
X1522700Y318067D01*
X1523940Y319316D01*
X1524560Y321192D01*
Y330150D01*
G01X1530450Y317650D02*
Y330150D01*
X1534325D01*
X1535565Y329525D01*
X1536340Y328692D01*
X1536650Y327025D01*
X1536340Y325358D01*
X1535410Y324317D01*
X1534325Y323692D01*
X1530450D01*
G01X1534325D02*
X1536650Y317650D01*
G01X1549050D02*
X1542850D01*
Y330150D01*
X1549050D01*
G01X1546570Y324108D02*
X1542850D01*
G01X1470000Y336400D02*
X1953600D01*
G01X1470000Y364500D02*
X1953600D01*
G01X1559900Y336400D02*
Y83500D01*
G01X1583925Y345750D02*
X1587800Y358250D01*
X1591675Y345750D01*
G01X1590280Y350125D02*
X1585320D01*
G01X1597100Y358250D02*
Y345750D01*
X1603300D01*
G01X1609500Y358250D02*
Y345750D01*
X1615700D01*
G01X1633990Y358250D02*
Y349292D01*
X1634610Y347416D01*
X1635850Y346167D01*
X1637400Y345750D01*
X1638950Y346167D01*
X1640190Y347416D01*
X1640810Y349292D01*
Y358250D01*
G01X1646235Y345750D02*
Y358250D01*
X1653365Y345750D01*
Y358250D01*
G01X1660340D02*
X1664060D01*
G01X1662200D02*
Y345750D01*
G01X1660340D02*
X1664060D01*
G01X1674600Y358250D02*
Y345750D01*
G01X1671035Y358250D02*
X1678165D01*
G01X1683745Y347416D02*
X1684985Y346375D01*
X1686380Y345750D01*
X1687620D01*
X1688860Y346375D01*
X1689790Y347416D01*
X1690255Y348875D01*
X1689945Y350333D01*
X1689170Y351583D01*
X1687775Y352417D01*
X1685915Y352833D01*
X1684830Y353667D01*
X1684365Y355125D01*
X1684675Y356583D01*
X1685450Y357625D01*
X1686535Y358250D01*
X1687620D01*
X1688705Y357833D01*
X1689635Y356792D01*
G01X1707925Y345750D02*
X1711800Y358250D01*
X1715675Y345750D01*
G01X1714280Y350125D02*
X1709320D01*
G01X1721100Y345750D02*
Y358250D01*
X1724975D01*
X1726215Y357625D01*
X1726990Y356792D01*
X1727300Y355125D01*
X1726990Y353458D01*
X1726060Y352417D01*
X1724975Y351792D01*
X1721100D01*
G01X1724975D02*
X1727300Y345750D01*
G01X1739700D02*
X1733500D01*
Y358250D01*
X1739700D01*
G01X1737220Y352208D02*
X1733500D01*
G01X1759540Y358250D02*
X1763260D01*
G01X1761400D02*
Y345750D01*
G01X1759540D02*
X1763260D01*
G01X1770235D02*
Y358250D01*
X1777365Y345750D01*
Y358250D01*
G01X1794570Y345750D02*
Y358250D01*
X1798600Y347833D01*
X1802630Y358250D01*
Y345750D01*
G01X1809140Y358250D02*
X1812860D01*
G01X1811000D02*
Y345750D01*
G01X1809140D02*
X1812860D01*
G01X1820300Y358250D02*
Y345750D01*
X1826500D01*
G01X1832545Y347416D02*
X1833785Y346375D01*
X1835180Y345750D01*
X1836420D01*
X1837660Y346375D01*
X1838590Y347416D01*
X1839055Y348875D01*
X1838745Y350333D01*
X1837970Y351583D01*
X1836575Y352417D01*
X1834715Y352833D01*
X1833630Y353667D01*
X1833165Y355125D01*
X1833475Y356583D01*
X1834250Y357625D01*
X1835335Y358250D01*
X1836420D01*
X1837505Y357833D01*
X1838435Y356792D01*
G01X1553390Y370750D02*
Y383250D01*
X1556490D01*
X1557730Y382625D01*
X1558660Y381792D01*
X1559435Y380542D01*
X1560055Y379083D01*
X1560210Y377000D01*
X1560055Y374917D01*
X1559435Y373458D01*
X1558660Y372208D01*
X1557730Y371375D01*
X1556490Y370750D01*
X1553390D01*
G01X1566100D02*
Y383250D01*
X1569975D01*
X1571215Y382625D01*
X1571990Y381792D01*
X1572300Y380125D01*
X1571990Y378458D01*
X1571060Y377417D01*
X1569975Y376792D01*
X1566100D01*
G01X1569975D02*
X1572300Y370750D01*
G01X1579740Y383250D02*
X1583460D01*
G01X1581600D02*
Y370750D01*
G01X1579740D02*
X1583460D01*
G01X1590900Y383250D02*
Y370750D01*
X1597100D01*
G01X1603300Y383250D02*
Y370750D01*
X1609500D01*
G01X1634610Y382208D02*
X1633680Y382833D01*
X1632595Y383250D01*
X1631355D01*
X1629960Y382625D01*
X1628875Y381583D01*
X1628100Y380333D01*
X1627480Y378250D01*
X1627325Y376375D01*
X1627635Y374500D01*
X1628100Y373250D01*
X1629030Y372000D01*
X1630115Y371167D01*
X1631200Y370750D01*
X1632285D01*
X1633370Y371167D01*
X1634300Y371791D01*
X1635075Y372625D01*
G01X1640345Y370750D02*
Y383250D01*
G01X1646855D02*
Y370750D01*
G01Y377000D02*
X1640345D01*
G01X1652125Y370750D02*
X1656000Y383250D01*
X1659875Y370750D01*
G01X1658480Y375125D02*
X1653520D01*
G01X1665300Y370750D02*
Y383250D01*
X1669175D01*
X1670415Y382625D01*
X1671190Y381792D01*
X1671500Y380125D01*
X1671190Y378458D01*
X1670260Y377417D01*
X1669175Y376792D01*
X1665300D01*
G01X1669175D02*
X1671500Y370750D01*
G01X1680800Y383250D02*
Y370750D01*
G01X1677235Y383250D02*
X1684365D01*
G01X1693200Y370333D02*
X1692890Y370542D01*
Y370958D01*
X1693200Y371167D01*
X1693510Y370958D01*
Y370542D01*
X1693200Y370333D01*
G01Y375958D02*
X1692890Y376167D01*
Y376583D01*
X1693200Y376792D01*
X1693510Y376583D01*
Y376167D01*
X1693200Y375958D01*
G01X1718000Y383250D02*
Y370750D01*
G01X1714435Y383250D02*
X1721565D01*
G01X1730400Y370750D02*
X1729160Y370958D01*
X1728075Y371791D01*
X1727145Y373042D01*
X1726525Y374500D01*
X1726215Y376167D01*
Y377833D01*
X1726525Y379500D01*
X1727145Y380958D01*
X1728075Y382208D01*
X1729160Y383042D01*
X1730400Y383250D01*
X1731640Y383042D01*
X1732725Y382208D01*
X1733655Y380958D01*
X1734275Y379500D01*
X1734585Y377833D01*
Y376167D01*
X1734275Y374500D01*
X1733655Y373042D01*
X1732725Y371791D01*
X1731640Y370958D01*
X1730400Y370750D01*
G01X1739700D02*
Y383250D01*
X1743420D01*
X1744660Y382625D01*
X1745590Y381167D01*
X1745900Y379500D01*
X1745590Y377833D01*
X1744815Y376583D01*
X1743420Y375958D01*
X1739700D01*
G01X1767600Y383250D02*
Y370750D01*
G01X1765430Y379083D02*
X1769770D01*
G01X1780000Y370750D02*
X1779070Y370958D01*
X1778140Y371791D01*
X1777520Y373250D01*
X1777210Y374917D01*
X1777520Y376583D01*
X1778140Y378042D01*
X1779070Y378875D01*
X1780000Y379083D01*
X1780930Y378875D01*
X1781860Y378042D01*
X1782480Y376583D01*
X1782635Y374917D01*
X1782480Y373250D01*
X1781860Y371791D01*
X1780930Y370958D01*
X1780000Y370750D01*
G01X1806040Y377417D02*
X1806660Y378042D01*
X1807125Y379083D01*
X1807435Y380542D01*
X1807125Y381792D01*
X1806505Y382625D01*
X1805420Y383250D01*
X1801235D01*
Y370750D01*
X1806350D01*
X1807435Y371583D01*
X1808055Y372833D01*
X1808365Y374292D01*
X1808055Y375750D01*
X1807125Y377000D01*
X1806040Y377417D01*
X1801235D01*
G01X1817200Y370750D02*
X1815960Y370958D01*
X1814875Y371791D01*
X1813945Y373042D01*
X1813325Y374500D01*
X1813015Y376167D01*
Y377833D01*
X1813325Y379500D01*
X1813945Y380958D01*
X1814875Y382208D01*
X1815960Y383042D01*
X1817200Y383250D01*
X1818440Y383042D01*
X1819525Y382208D01*
X1820455Y380958D01*
X1821075Y379500D01*
X1821385Y377833D01*
Y376167D01*
X1821075Y374500D01*
X1820455Y373042D01*
X1819525Y371791D01*
X1818440Y370958D01*
X1817200Y370750D01*
G01X1829600Y383250D02*
Y370750D01*
G01X1826035Y383250D02*
X1833165D01*
G01X1842000D02*
Y370750D01*
G01X1838435Y383250D02*
X1845565D01*
G01X1854400Y370750D02*
X1853160Y370958D01*
X1852075Y371791D01*
X1851145Y373042D01*
X1850525Y374500D01*
X1850215Y376167D01*
Y377833D01*
X1850525Y379500D01*
X1851145Y380958D01*
X1852075Y382208D01*
X1853160Y383042D01*
X1854400Y383250D01*
X1855640Y383042D01*
X1856725Y382208D01*
X1857655Y380958D01*
X1858275Y379500D01*
X1858585Y377833D01*
Y376167D01*
X1858275Y374500D01*
X1857655Y373042D01*
X1856725Y371791D01*
X1855640Y370958D01*
X1854400Y370750D01*
G01X1862770D02*
Y383250D01*
X1866800Y372833D01*
X1870830Y383250D01*
Y370750D01*
G01X1629650Y91300D02*
Y103800D01*
X1627790Y101300D01*
G01Y91300D02*
X1631510D01*
G01X1638640Y93175D02*
X1639570Y92133D01*
X1640655Y91508D01*
X1642050Y91300D01*
X1643445Y91717D01*
X1644530Y92550D01*
X1645305Y94008D01*
X1645460Y95675D01*
X1645150Y97342D01*
X1644375Y98383D01*
X1643290Y99217D01*
X1642205Y99425D01*
X1641120Y99217D01*
X1639725Y98383D01*
X1640190Y103800D01*
X1644375D01*
G01X1654450Y91300D02*
X1655535Y91508D01*
X1656775Y92133D01*
X1657550Y93175D01*
X1657860Y94633D01*
X1657550Y96091D01*
X1656620Y97342D01*
X1655225Y97967D01*
X1653675D01*
X1652745Y98383D01*
X1651970Y99425D01*
X1651660Y100883D01*
X1652125Y102342D01*
X1653210Y103383D01*
X1654450Y103800D01*
X1655690Y103383D01*
X1656775Y102342D01*
X1657240Y100883D01*
X1656930Y99425D01*
X1656155Y98383D01*
X1655225Y97967D01*
X1653675D01*
X1652280Y97342D01*
X1651350Y96091D01*
X1651040Y94633D01*
X1651350Y93175D01*
X1652125Y92133D01*
X1653365Y91508D01*
X1654450Y91300D01*
G01X1666850Y90883D02*
X1666540Y91092D01*
Y91508D01*
X1666850Y91717D01*
X1667160Y91508D01*
Y91092D01*
X1666850Y90883D01*
G01X1679250Y103800D02*
X1678010Y103383D01*
X1677080Y102342D01*
X1676460Y101092D01*
X1675995Y99425D01*
X1675840Y97550D01*
X1675995Y95675D01*
X1676460Y94008D01*
X1677080Y92758D01*
X1678010Y91717D01*
X1679250Y91300D01*
X1680490Y91717D01*
X1681420Y92758D01*
X1682040Y94008D01*
X1682505Y95675D01*
X1682660Y97550D01*
X1682505Y99425D01*
X1682040Y101092D01*
X1681420Y102342D01*
X1680490Y103383D01*
X1679250Y103800D01*
G01X1635850Y119400D02*
X1636935Y119608D01*
X1638175Y120233D01*
X1638950Y121275D01*
X1639260Y122733D01*
X1638950Y124191D01*
X1638020Y125442D01*
X1636625Y126067D01*
X1635075D01*
X1634145Y126483D01*
X1633370Y127525D01*
X1633060Y128983D01*
X1633525Y130442D01*
X1634610Y131483D01*
X1635850Y131900D01*
X1637090Y131483D01*
X1638175Y130442D01*
X1638640Y128983D01*
X1638330Y127525D01*
X1637555Y126483D01*
X1636625Y126067D01*
X1635075D01*
X1633680Y125442D01*
X1632750Y124191D01*
X1632440Y122733D01*
X1632750Y121275D01*
X1633525Y120233D01*
X1634765Y119608D01*
X1635850Y119400D01*
G01X1645305Y124608D02*
X1646390Y126067D01*
X1647320Y126900D01*
X1648560Y127317D01*
X1649645Y126900D01*
X1650420Y126067D01*
X1651040Y124817D01*
X1651195Y123358D01*
X1651040Y122108D01*
X1650420Y120858D01*
X1649490Y119817D01*
X1648405Y119400D01*
X1647165Y119817D01*
X1646080Y121066D01*
X1645460Y122942D01*
X1645305Y125025D01*
X1645615Y127733D01*
X1646080Y129192D01*
X1646855Y130650D01*
X1647940Y131692D01*
X1649025Y131900D01*
X1650110Y131483D01*
X1650885Y130442D01*
G01X1660650Y118983D02*
X1660340Y119192D01*
Y119608D01*
X1660650Y119817D01*
X1660960Y119608D01*
Y119192D01*
X1660650Y118983D01*
G01X1673050Y131900D02*
X1671810Y131483D01*
X1670880Y130442D01*
X1670260Y129192D01*
X1669795Y127525D01*
X1669640Y125650D01*
X1669795Y123775D01*
X1670260Y122108D01*
X1670880Y120858D01*
X1671810Y119817D01*
X1673050Y119400D01*
X1674290Y119817D01*
X1675220Y120858D01*
X1675840Y122108D01*
X1676305Y123775D01*
X1676460Y125650D01*
X1676305Y127525D01*
X1675840Y129192D01*
X1675220Y130442D01*
X1674290Y131483D01*
X1673050Y131900D01*
G01X1632440Y150000D02*
X1633370Y148541D01*
X1634610Y147708D01*
X1636005Y147500D01*
X1637245Y147708D01*
X1638485Y148750D01*
X1639260Y150000D01*
X1639415Y151250D01*
X1639105Y152708D01*
X1638020Y153750D01*
X1636935Y154167D01*
X1635540D01*
G01X1636935D02*
X1637865Y154792D01*
X1638640Y155833D01*
X1638950Y157083D01*
X1638640Y158333D01*
X1637865Y159375D01*
X1636470Y160000D01*
X1635075Y159792D01*
X1633680Y158958D01*
G01X1650110Y147500D02*
Y160000D01*
X1644375Y151042D01*
X1652125D01*
G01X1660650Y147083D02*
X1660340Y147292D01*
Y147708D01*
X1660650Y147917D01*
X1660960Y147708D01*
Y147292D01*
X1660650Y147083D01*
G01X1673050Y160000D02*
X1671810Y159583D01*
X1670880Y158542D01*
X1670260Y157292D01*
X1669795Y155625D01*
X1669640Y153750D01*
X1669795Y151875D01*
X1670260Y150208D01*
X1670880Y148958D01*
X1671810Y147917D01*
X1673050Y147500D01*
X1674290Y147917D01*
X1675220Y148958D01*
X1675840Y150208D01*
X1676305Y151875D01*
X1676460Y153750D01*
X1676305Y155625D01*
X1675840Y157292D01*
X1675220Y158542D01*
X1674290Y159583D01*
X1673050Y160000D01*
G01X1629650Y175600D02*
Y188100D01*
X1627790Y185600D01*
G01Y175600D02*
X1631510D01*
G01X1638640Y177475D02*
X1639570Y176433D01*
X1640655Y175808D01*
X1642050Y175600D01*
X1643445Y176017D01*
X1644530Y176850D01*
X1645305Y178308D01*
X1645460Y179975D01*
X1645150Y181642D01*
X1644375Y182683D01*
X1643290Y183517D01*
X1642205Y183725D01*
X1641120Y183517D01*
X1639725Y182683D01*
X1640190Y188100D01*
X1644375D01*
G01X1654450Y175600D02*
X1655535Y175808D01*
X1656775Y176433D01*
X1657550Y177475D01*
X1657860Y178933D01*
X1657550Y180391D01*
X1656620Y181642D01*
X1655225Y182267D01*
X1653675D01*
X1652745Y182683D01*
X1651970Y183725D01*
X1651660Y185183D01*
X1652125Y186642D01*
X1653210Y187683D01*
X1654450Y188100D01*
X1655690Y187683D01*
X1656775Y186642D01*
X1657240Y185183D01*
X1656930Y183725D01*
X1656155Y182683D01*
X1655225Y182267D01*
X1653675D01*
X1652280Y181642D01*
X1651350Y180391D01*
X1651040Y178933D01*
X1651350Y177475D01*
X1652125Y176433D01*
X1653365Y175808D01*
X1654450Y175600D01*
G01X1666850Y175183D02*
X1666540Y175392D01*
Y175808D01*
X1666850Y176017D01*
X1667160Y175808D01*
Y175392D01*
X1666850Y175183D01*
G01X1679250Y188100D02*
X1678010Y187683D01*
X1677080Y186642D01*
X1676460Y185392D01*
X1675995Y183725D01*
X1675840Y181850D01*
X1675995Y179975D01*
X1676460Y178308D01*
X1677080Y177058D01*
X1678010Y176017D01*
X1679250Y175600D01*
X1680490Y176017D01*
X1681420Y177058D01*
X1682040Y178308D01*
X1682505Y179975D01*
X1682660Y181850D01*
X1682505Y183725D01*
X1682040Y185392D01*
X1681420Y186642D01*
X1680490Y187683D01*
X1679250Y188100D01*
G01X1629650Y203700D02*
Y216200D01*
X1627790Y213700D01*
G01Y203700D02*
X1631510D01*
G01X1643910D02*
Y216200D01*
X1638175Y207242D01*
X1645925D01*
G01X1654450Y216200D02*
X1653210Y215783D01*
X1652280Y214742D01*
X1651660Y213492D01*
X1651195Y211825D01*
X1651040Y209950D01*
X1651195Y208075D01*
X1651660Y206408D01*
X1652280Y205158D01*
X1653210Y204117D01*
X1654450Y203700D01*
X1655690Y204117D01*
X1656620Y205158D01*
X1657240Y206408D01*
X1657705Y208075D01*
X1657860Y209950D01*
X1657705Y211825D01*
X1657240Y213492D01*
X1656620Y214742D01*
X1655690Y215783D01*
X1654450Y216200D01*
G01X1666850Y203283D02*
X1666540Y203492D01*
Y203908D01*
X1666850Y204117D01*
X1667160Y203908D01*
Y203492D01*
X1666850Y203283D01*
G01X1679250Y216200D02*
X1678010Y215783D01*
X1677080Y214742D01*
X1676460Y213492D01*
X1675995Y211825D01*
X1675840Y209950D01*
X1675995Y208075D01*
X1676460Y206408D01*
X1677080Y205158D01*
X1678010Y204117D01*
X1679250Y203700D01*
X1680490Y204117D01*
X1681420Y205158D01*
X1682040Y206408D01*
X1682505Y208075D01*
X1682660Y209950D01*
X1682505Y211825D01*
X1682040Y213492D01*
X1681420Y214742D01*
X1680490Y215783D01*
X1679250Y216200D01*
G01X1637710Y231800D02*
Y244300D01*
X1631975Y235342D01*
X1639725D01*
G01X1648250Y231800D02*
Y244300D01*
X1646390Y241800D01*
G01Y231800D02*
X1650110D01*
G01X1660650Y231383D02*
X1660340Y231592D01*
Y232008D01*
X1660650Y232217D01*
X1660960Y232008D01*
Y231592D01*
X1660650Y231383D01*
G01X1673050Y244300D02*
X1671810Y243883D01*
X1670880Y242842D01*
X1670260Y241592D01*
X1669795Y239925D01*
X1669640Y238050D01*
X1669795Y236175D01*
X1670260Y234508D01*
X1670880Y233258D01*
X1671810Y232217D01*
X1673050Y231800D01*
X1674290Y232217D01*
X1675220Y233258D01*
X1675840Y234508D01*
X1676305Y236175D01*
X1676460Y238050D01*
X1676305Y239925D01*
X1675840Y241592D01*
X1675220Y242842D01*
X1674290Y243883D01*
X1673050Y244300D01*
G01X1632440Y262400D02*
X1633370Y260941D01*
X1634610Y260108D01*
X1636005Y259900D01*
X1637245Y260108D01*
X1638485Y261150D01*
X1639260Y262400D01*
X1639415Y263650D01*
X1639105Y265108D01*
X1638020Y266150D01*
X1636935Y266567D01*
X1635540D01*
G01X1636935D02*
X1637865Y267192D01*
X1638640Y268233D01*
X1638950Y269483D01*
X1638640Y270733D01*
X1637865Y271775D01*
X1636470Y272400D01*
X1635075Y272192D01*
X1633680Y271358D01*
G01X1647940Y259900D02*
X1648250Y262608D01*
X1648715Y264900D01*
X1649335Y266983D01*
X1650110Y269275D01*
X1651350Y272400D01*
X1645150D01*
G01X1660650Y259483D02*
X1660340Y259692D01*
Y260108D01*
X1660650Y260317D01*
X1660960Y260108D01*
Y259692D01*
X1660650Y259483D01*
G01X1673050Y272400D02*
X1671810Y271983D01*
X1670880Y270942D01*
X1670260Y269692D01*
X1669795Y268025D01*
X1669640Y266150D01*
X1669795Y264275D01*
X1670260Y262608D01*
X1670880Y261358D01*
X1671810Y260317D01*
X1673050Y259900D01*
X1674290Y260317D01*
X1675220Y261358D01*
X1675840Y262608D01*
X1676305Y264275D01*
X1676460Y266150D01*
X1676305Y268025D01*
X1675840Y269692D01*
X1675220Y270942D01*
X1674290Y271983D01*
X1673050Y272400D01*
G01X1635850Y288000D02*
Y300500D01*
X1633990Y298000D01*
G01Y288000D02*
X1637710D01*
G01X1645305Y293208D02*
X1646390Y294667D01*
X1647320Y295500D01*
X1648560Y295917D01*
X1649645Y295500D01*
X1650420Y294667D01*
X1651040Y293417D01*
X1651195Y291958D01*
X1651040Y290708D01*
X1650420Y289458D01*
X1649490Y288417D01*
X1648405Y288000D01*
X1647165Y288417D01*
X1646080Y289666D01*
X1645460Y291542D01*
X1645305Y293625D01*
X1645615Y296333D01*
X1646080Y297792D01*
X1646855Y299250D01*
X1647940Y300292D01*
X1649025Y300500D01*
X1650110Y300083D01*
X1650885Y299042D01*
G01X1660650Y287583D02*
X1660340Y287792D01*
Y288208D01*
X1660650Y288417D01*
X1660960Y288208D01*
Y287792D01*
X1660650Y287583D01*
G01X1673050Y300500D02*
X1671810Y300083D01*
X1670880Y299042D01*
X1670260Y297792D01*
X1669795Y296125D01*
X1669640Y294250D01*
X1669795Y292375D01*
X1670260Y290708D01*
X1670880Y289458D01*
X1671810Y288417D01*
X1673050Y288000D01*
X1674290Y288417D01*
X1675220Y289458D01*
X1675840Y290708D01*
X1676305Y292375D01*
X1676460Y294250D01*
X1676305Y296125D01*
X1675840Y297792D01*
X1675220Y299042D01*
X1674290Y300083D01*
X1673050Y300500D01*
G01X1632595Y319316D02*
X1633835Y318275D01*
X1635230Y317650D01*
X1636470D01*
X1637710Y318275D01*
X1638640Y319316D01*
X1639105Y320775D01*
X1638795Y322233D01*
X1638020Y323483D01*
X1636625Y324317D01*
X1634765Y324733D01*
X1633680Y325567D01*
X1633215Y327025D01*
X1633525Y328483D01*
X1634300Y329525D01*
X1635385Y330150D01*
X1636470D01*
X1637555Y329733D01*
X1638485Y328692D01*
G01X1646390Y330150D02*
X1650110D01*
G01X1648250D02*
Y317650D01*
G01X1646390D02*
X1650110D01*
G01X1657705Y330150D02*
X1663595D01*
X1657705Y317650D01*
X1663595D01*
G01X1676150D02*
X1669950D01*
Y330150D01*
X1676150D01*
G01X1673670Y324108D02*
X1669950D01*
G01X1753185Y91300D02*
Y103800D01*
X1760315Y91300D01*
Y103800D01*
G01X1769150Y91300D02*
X1767910Y91508D01*
X1766825Y92341D01*
X1765895Y93592D01*
X1765275Y95050D01*
X1764965Y96717D01*
Y98383D01*
X1765275Y100050D01*
X1765895Y101508D01*
X1766825Y102758D01*
X1767910Y103592D01*
X1769150Y103800D01*
X1770390Y103592D01*
X1771475Y102758D01*
X1772405Y101508D01*
X1773025Y100050D01*
X1773335Y98383D01*
Y96717D01*
X1773025Y95050D01*
X1772405Y93592D01*
X1771475Y92341D01*
X1770390Y91508D01*
X1769150Y91300D01*
G01X1777985D02*
Y103800D01*
X1785115Y91300D01*
Y103800D01*
G01X1791935Y95467D02*
X1795965D01*
G01X1803250Y91300D02*
Y103800D01*
X1806970D01*
X1808210Y103175D01*
X1809140Y101717D01*
X1809450Y100050D01*
X1809140Y98383D01*
X1808365Y97133D01*
X1806970Y96508D01*
X1803250D01*
G01X1815650Y103800D02*
Y91300D01*
X1821850D01*
G01X1827275D02*
X1831150Y103800D01*
X1835025Y91300D01*
G01X1833630Y95675D02*
X1828670D01*
G01X1843550Y103800D02*
Y91300D01*
G01X1839985Y103800D02*
X1847115D01*
G01X1859050Y91300D02*
X1852850D01*
Y103800D01*
X1859050D01*
G01X1856570Y97758D02*
X1852850D01*
G01X1864940Y91300D02*
Y103800D01*
X1868040D01*
X1869280Y103175D01*
X1870210Y102342D01*
X1870985Y101092D01*
X1871605Y99633D01*
X1871760Y97550D01*
X1871605Y95467D01*
X1870985Y94008D01*
X1870210Y92758D01*
X1869280Y91925D01*
X1868040Y91300D01*
X1864940D01*
G01X1749000Y336400D02*
Y83500D01*
G01X1753185Y119400D02*
Y131900D01*
X1760315Y119400D01*
Y131900D01*
G01X1769150Y119400D02*
X1767910Y119608D01*
X1766825Y120441D01*
X1765895Y121692D01*
X1765275Y123150D01*
X1764965Y124817D01*
Y126483D01*
X1765275Y128150D01*
X1765895Y129608D01*
X1766825Y130858D01*
X1767910Y131692D01*
X1769150Y131900D01*
X1770390Y131692D01*
X1771475Y130858D01*
X1772405Y129608D01*
X1773025Y128150D01*
X1773335Y126483D01*
Y124817D01*
X1773025Y123150D01*
X1772405Y121692D01*
X1771475Y120441D01*
X1770390Y119608D01*
X1769150Y119400D01*
G01X1777985D02*
Y131900D01*
X1785115Y119400D01*
Y131900D01*
G01X1791935Y123567D02*
X1795965D01*
G01X1803250Y119400D02*
Y131900D01*
X1806970D01*
X1808210Y131275D01*
X1809140Y129817D01*
X1809450Y128150D01*
X1809140Y126483D01*
X1808365Y125233D01*
X1806970Y124608D01*
X1803250D01*
G01X1815650Y131900D02*
Y119400D01*
X1821850D01*
G01X1827275D02*
X1831150Y131900D01*
X1835025Y119400D01*
G01X1833630Y123775D02*
X1828670D01*
G01X1843550Y131900D02*
Y119400D01*
G01X1839985Y131900D02*
X1847115D01*
G01X1859050Y119400D02*
X1852850D01*
Y131900D01*
X1859050D01*
G01X1856570Y125858D02*
X1852850D01*
G01X1864940Y119400D02*
Y131900D01*
X1868040D01*
X1869280Y131275D01*
X1870210Y130442D01*
X1870985Y129192D01*
X1871605Y127733D01*
X1871760Y125650D01*
X1871605Y123567D01*
X1870985Y122108D01*
X1870210Y120858D01*
X1869280Y120025D01*
X1868040Y119400D01*
X1864940D01*
G01X1753185Y147500D02*
Y160000D01*
X1760315Y147500D01*
Y160000D01*
G01X1769150Y147500D02*
X1767910Y147708D01*
X1766825Y148541D01*
X1765895Y149792D01*
X1765275Y151250D01*
X1764965Y152917D01*
Y154583D01*
X1765275Y156250D01*
X1765895Y157708D01*
X1766825Y158958D01*
X1767910Y159792D01*
X1769150Y160000D01*
X1770390Y159792D01*
X1771475Y158958D01*
X1772405Y157708D01*
X1773025Y156250D01*
X1773335Y154583D01*
Y152917D01*
X1773025Y151250D01*
X1772405Y149792D01*
X1771475Y148541D01*
X1770390Y147708D01*
X1769150Y147500D01*
G01X1777985D02*
Y160000D01*
X1785115Y147500D01*
Y160000D01*
G01X1791935Y151667D02*
X1795965D01*
G01X1803250Y147500D02*
Y160000D01*
X1806970D01*
X1808210Y159375D01*
X1809140Y157917D01*
X1809450Y156250D01*
X1809140Y154583D01*
X1808365Y153333D01*
X1806970Y152708D01*
X1803250D01*
G01X1815650Y160000D02*
Y147500D01*
X1821850D01*
G01X1827275D02*
X1831150Y160000D01*
X1835025Y147500D01*
G01X1833630Y151875D02*
X1828670D01*
G01X1843550Y160000D02*
Y147500D01*
G01X1839985Y160000D02*
X1847115D01*
G01X1859050Y147500D02*
X1852850D01*
Y160000D01*
X1859050D01*
G01X1856570Y153958D02*
X1852850D01*
G01X1864940Y147500D02*
Y160000D01*
X1868040D01*
X1869280Y159375D01*
X1870210Y158542D01*
X1870985Y157292D01*
X1871605Y155833D01*
X1871760Y153750D01*
X1871605Y151667D01*
X1870985Y150208D01*
X1870210Y148958D01*
X1869280Y148125D01*
X1868040Y147500D01*
X1864940D01*
G01X1778450Y175600D02*
Y188100D01*
X1782170D01*
X1783410Y187475D01*
X1784340Y186017D01*
X1784650Y184350D01*
X1784340Y182683D01*
X1783565Y181433D01*
X1782170Y180808D01*
X1778450D01*
G01X1790850Y188100D02*
Y175600D01*
X1797050D01*
G01X1802475D02*
X1806350Y188100D01*
X1810225Y175600D01*
G01X1808830Y179975D02*
X1803870D01*
G01X1818750Y188100D02*
Y175600D01*
G01X1815185Y188100D02*
X1822315D01*
G01X1834250Y175600D02*
X1828050D01*
Y188100D01*
X1834250D01*
G01X1831770Y182058D02*
X1828050D01*
G01X1840140Y175600D02*
Y188100D01*
X1843240D01*
X1844480Y187475D01*
X1845410Y186642D01*
X1846185Y185392D01*
X1846805Y183933D01*
X1846960Y181850D01*
X1846805Y179767D01*
X1846185Y178308D01*
X1845410Y177058D01*
X1844480Y176225D01*
X1843240Y175600D01*
X1840140D01*
G01X1778450Y203700D02*
Y216200D01*
X1782170D01*
X1783410Y215575D01*
X1784340Y214117D01*
X1784650Y212450D01*
X1784340Y210783D01*
X1783565Y209533D01*
X1782170Y208908D01*
X1778450D01*
G01X1790850Y216200D02*
Y203700D01*
X1797050D01*
G01X1802475D02*
X1806350Y216200D01*
X1810225Y203700D01*
G01X1808830Y208075D02*
X1803870D01*
G01X1818750Y216200D02*
Y203700D01*
G01X1815185Y216200D02*
X1822315D01*
G01X1834250Y203700D02*
X1828050D01*
Y216200D01*
X1834250D01*
G01X1831770Y210158D02*
X1828050D01*
G01X1840140Y203700D02*
Y216200D01*
X1843240D01*
X1844480Y215575D01*
X1845410Y214742D01*
X1846185Y213492D01*
X1846805Y212033D01*
X1846960Y209950D01*
X1846805Y207867D01*
X1846185Y206408D01*
X1845410Y205158D01*
X1844480Y204325D01*
X1843240Y203700D01*
X1840140D01*
G01X1778450Y231800D02*
Y244300D01*
X1782170D01*
X1783410Y243675D01*
X1784340Y242217D01*
X1784650Y240550D01*
X1784340Y238883D01*
X1783565Y237633D01*
X1782170Y237008D01*
X1778450D01*
G01X1790850Y244300D02*
Y231800D01*
X1797050D01*
G01X1802475D02*
X1806350Y244300D01*
X1810225Y231800D01*
G01X1808830Y236175D02*
X1803870D01*
G01X1818750Y244300D02*
Y231800D01*
G01X1815185Y244300D02*
X1822315D01*
G01X1834250Y231800D02*
X1828050D01*
Y244300D01*
X1834250D01*
G01X1831770Y238258D02*
X1828050D01*
G01X1840140Y231800D02*
Y244300D01*
X1843240D01*
X1844480Y243675D01*
X1845410Y242842D01*
X1846185Y241592D01*
X1846805Y240133D01*
X1846960Y238050D01*
X1846805Y235967D01*
X1846185Y234508D01*
X1845410Y233258D01*
X1844480Y232425D01*
X1843240Y231800D01*
X1840140D01*
G01X1778450Y259900D02*
Y272400D01*
X1782170D01*
X1783410Y271775D01*
X1784340Y270317D01*
X1784650Y268650D01*
X1784340Y266983D01*
X1783565Y265733D01*
X1782170Y265108D01*
X1778450D01*
G01X1790850Y272400D02*
Y259900D01*
X1797050D01*
G01X1802475D02*
X1806350Y272400D01*
X1810225Y259900D01*
G01X1808830Y264275D02*
X1803870D01*
G01X1818750Y272400D02*
Y259900D01*
G01X1815185Y272400D02*
X1822315D01*
G01X1834250Y259900D02*
X1828050D01*
Y272400D01*
X1834250D01*
G01X1831770Y266358D02*
X1828050D01*
G01X1840140Y259900D02*
Y272400D01*
X1843240D01*
X1844480Y271775D01*
X1845410Y270942D01*
X1846185Y269692D01*
X1846805Y268233D01*
X1846960Y266150D01*
X1846805Y264067D01*
X1846185Y262608D01*
X1845410Y261358D01*
X1844480Y260525D01*
X1843240Y259900D01*
X1840140D01*
G01X1778450Y288000D02*
Y300500D01*
X1782170D01*
X1783410Y299875D01*
X1784340Y298417D01*
X1784650Y296750D01*
X1784340Y295083D01*
X1783565Y293833D01*
X1782170Y293208D01*
X1778450D01*
G01X1790850Y300500D02*
Y288000D01*
X1797050D01*
G01X1802475D02*
X1806350Y300500D01*
X1810225Y288000D01*
G01X1808830Y292375D02*
X1803870D01*
G01X1818750Y300500D02*
Y288000D01*
G01X1815185Y300500D02*
X1822315D01*
G01X1834250Y288000D02*
X1828050D01*
Y300500D01*
X1834250D01*
G01X1831770Y294458D02*
X1828050D01*
G01X1840140Y288000D02*
Y300500D01*
X1843240D01*
X1844480Y299875D01*
X1845410Y299042D01*
X1846185Y297792D01*
X1846805Y296333D01*
X1846960Y294250D01*
X1846805Y292167D01*
X1846185Y290708D01*
X1845410Y289458D01*
X1844480Y288625D01*
X1843240Y288000D01*
X1840140D01*
G01X1778450Y317650D02*
Y330150D01*
X1782170D01*
X1783410Y329525D01*
X1784340Y328067D01*
X1784650Y326400D01*
X1784340Y324733D01*
X1783565Y323483D01*
X1782170Y322858D01*
X1778450D01*
G01X1790850Y330150D02*
Y317650D01*
X1797050D01*
G01X1802475D02*
X1806350Y330150D01*
X1810225Y317650D01*
G01X1808830Y322025D02*
X1803870D01*
G01X1818750Y330150D02*
Y317650D01*
G01X1815185Y330150D02*
X1822315D01*
G01X1834250Y317650D02*
X1828050D01*
Y330150D01*
X1834250D01*
G01X1831770Y324108D02*
X1828050D01*
G01X1840140Y317650D02*
Y330150D01*
X1843240D01*
X1844480Y329525D01*
X1845410Y328692D01*
X1846185Y327442D01*
X1846805Y325983D01*
X1846960Y323900D01*
X1846805Y321817D01*
X1846185Y320358D01*
X1845410Y319108D01*
X1844480Y318275D01*
X1843240Y317650D01*
X1840140D01*
G01X1876100Y336400D02*
Y83500D01*
G01X1911905Y101717D02*
X1912835Y102966D01*
X1913920Y103592D01*
X1915160Y103800D01*
X1916710Y103383D01*
X1917795Y102342D01*
X1918105Y101092D01*
X1917950Y99841D01*
X1917330Y98800D01*
X1914230Y96717D01*
X1912835Y95258D01*
X1911905Y93175D01*
X1911595Y91300D01*
X1918105D01*
G01X1911440Y121900D02*
X1912370Y120441D01*
X1913610Y119608D01*
X1915005Y119400D01*
X1916245Y119608D01*
X1917485Y120650D01*
X1918260Y121900D01*
X1918415Y123150D01*
X1918105Y124608D01*
X1917020Y125650D01*
X1915935Y126067D01*
X1914540D01*
G01X1915935D02*
X1916865Y126692D01*
X1917640Y127733D01*
X1917950Y128983D01*
X1917640Y130233D01*
X1916865Y131275D01*
X1915470Y131900D01*
X1914075Y131692D01*
X1912680Y130858D01*
G01X1911905Y157917D02*
X1912835Y159166D01*
X1913920Y159792D01*
X1915160Y160000D01*
X1916710Y159583D01*
X1917795Y158542D01*
X1918105Y157292D01*
X1917950Y156041D01*
X1917330Y155000D01*
X1914230Y152917D01*
X1912835Y151458D01*
X1911905Y149375D01*
X1911595Y147500D01*
X1918105D01*
G01X1911905Y186017D02*
X1912835Y187266D01*
X1913920Y187892D01*
X1915160Y188100D01*
X1916710Y187683D01*
X1917795Y186642D01*
X1918105Y185392D01*
X1917950Y184141D01*
X1917330Y183100D01*
X1914230Y181017D01*
X1912835Y179558D01*
X1911905Y177475D01*
X1911595Y175600D01*
X1918105D01*
G01X1911905Y214117D02*
X1912835Y215366D01*
X1913920Y215992D01*
X1915160Y216200D01*
X1916710Y215783D01*
X1917795Y214742D01*
X1918105Y213492D01*
X1917950Y212241D01*
X1917330Y211200D01*
X1914230Y209117D01*
X1912835Y207658D01*
X1911905Y205575D01*
X1911595Y203700D01*
X1918105D01*
G01X1905240Y233675D02*
X1906170Y232633D01*
X1907255Y232008D01*
X1908650Y231800D01*
X1910045Y232217D01*
X1911130Y233050D01*
X1911905Y234508D01*
X1912060Y236175D01*
X1911750Y237842D01*
X1910975Y238883D01*
X1909890Y239717D01*
X1908805Y239925D01*
X1907720Y239717D01*
X1906325Y238883D01*
X1906790Y244300D01*
X1910975D01*
G01X1918105Y242217D02*
X1919035Y243466D01*
X1920120Y244092D01*
X1921360Y244300D01*
X1922910Y243883D01*
X1923995Y242842D01*
X1924305Y241592D01*
X1924150Y240341D01*
X1923530Y239300D01*
X1920430Y237217D01*
X1919035Y235758D01*
X1918105Y233675D01*
X1917795Y231800D01*
X1924305D01*
G01X1911440Y262400D02*
X1912370Y260941D01*
X1913610Y260108D01*
X1915005Y259900D01*
X1916245Y260108D01*
X1917485Y261150D01*
X1918260Y262400D01*
X1918415Y263650D01*
X1918105Y265108D01*
X1917020Y266150D01*
X1915935Y266567D01*
X1914540D01*
G01X1915935D02*
X1916865Y267192D01*
X1917640Y268233D01*
X1917950Y269483D01*
X1917640Y270733D01*
X1916865Y271775D01*
X1915470Y272400D01*
X1914075Y272192D01*
X1912680Y271358D01*
G01X1902140Y288000D02*
X1902450Y290708D01*
X1902915Y293000D01*
X1903535Y295083D01*
X1904310Y297375D01*
X1905550Y300500D01*
X1899350D01*
G01X1914850Y288000D02*
X1915935Y288208D01*
X1917175Y288833D01*
X1917950Y289875D01*
X1918260Y291333D01*
X1917950Y292791D01*
X1917020Y294042D01*
X1915625Y294667D01*
X1914075D01*
X1913145Y295083D01*
X1912370Y296125D01*
X1912060Y297583D01*
X1912525Y299042D01*
X1913610Y300083D01*
X1914850Y300500D01*
X1916090Y300083D01*
X1917175Y299042D01*
X1917640Y297583D01*
X1917330Y296125D01*
X1916555Y295083D01*
X1915625Y294667D01*
X1914075D01*
X1912680Y294042D01*
X1911750Y292791D01*
X1911440Y291333D01*
X1911750Y289875D01*
X1912525Y288833D01*
X1913765Y288208D01*
X1914850Y288000D01*
G01X1924615Y289458D02*
X1925700Y288417D01*
X1926940Y288000D01*
X1928180Y288417D01*
X1929265Y289666D01*
X1930040Y291542D01*
X1930350Y293417D01*
Y295708D01*
X1930040Y297583D01*
X1929265Y299250D01*
X1928335Y300083D01*
X1927250Y300500D01*
X1926010Y300083D01*
X1925080Y299250D01*
X1924460Y298000D01*
X1924150Y296333D01*
X1924460Y294875D01*
X1925235Y293417D01*
X1926165Y292583D01*
X1927250Y292375D01*
X1928490Y292791D01*
X1929420Y293833D01*
X1930350Y295708D01*
G01X1902450Y317650D02*
X1901210Y317858D01*
X1900125Y318691D01*
X1899195Y319942D01*
X1898575Y321400D01*
X1898265Y323067D01*
Y324733D01*
X1898575Y326400D01*
X1899195Y327858D01*
X1900125Y329108D01*
X1901210Y329942D01*
X1902450Y330150D01*
X1903690Y329942D01*
X1904775Y329108D01*
X1905705Y327858D01*
X1906325Y326400D01*
X1906635Y324733D01*
Y323067D01*
X1906325Y321400D01*
X1905705Y319942D01*
X1904775Y318691D01*
X1903690Y317858D01*
X1902450Y317650D01*
G01X1903690Y320983D02*
X1905550Y317650D01*
G01X1914850Y330150D02*
Y317650D01*
G01X1911285Y330150D02*
X1918415D01*
G01X1927250Y317650D02*
Y323275D01*
X1924150Y330150D01*
G01X1930350D02*
X1927250Y323275D01*
G01X620709Y114409D02*
Y334409D01*
G01X633676Y217709D02*
X634009Y218242D01*
X634209Y218842D01*
Y219376D01*
X634009Y219909D01*
X633676Y220309D01*
X633209Y220509D01*
X632742Y220376D01*
X632342Y220042D01*
X632076Y219442D01*
X631942Y218642D01*
X631676Y218176D01*
X631209Y217976D01*
X630742Y218109D01*
X630409Y218442D01*
X630209Y218909D01*
Y219376D01*
X630342Y219842D01*
X630676Y220242D01*
G01X634209Y223709D02*
X630209D01*
G01X631542Y228309D02*
X634209D01*
G01X630476D02*
X630409Y228176D01*
X630276D01*
X630209Y228309D01*
X630276Y228442D01*
X630409D01*
X630476Y228309D01*
G01X630209Y232909D02*
X634209D01*
G01X631542Y231976D02*
Y233842D01*
G01X621209Y226509D02*
X625209Y222509D01*
Y230509D01*
X621209Y226509D01*
X631209D01*
M02*
